G04 ================== begin FILE IDENTIFICATION RECORD ==================*
G04 Layout Name:  9051_F0T_Panel_BD_Front_D_v02_20221209_1310.brd*
G04 Film Name:    top.art*
G04 File Format:  Gerber RS274X*
G04 File Origin:  Cadence Allegro 17.2-S081*
G04 Origin Date:  Mon Dec 12 15:51:17 2022*
G04 *
G04 Layer:  DRAWING FORMAT/TITLE_BLOCK_A*
G04 Layer:  PIN/SPECIAL_DRILL*
G04 Layer:  DRAWING FORMAT/TITLE_BLOCK*
G04 Layer:  VIA CLASS/TOP*
G04 Layer:  PIN/TOP*
G04 Layer:  MANUFACTURING/PHOTOPLOT_OUTLINE*
G04 Layer:  ETCH/TOP*
G04 Layer:  DRAWING FORMAT/TITLE_DATA_TOP*
G04 *
G04 Offset:    (0.00 0.00)*
G04 Mirror:    No*
G04 Mode:      Positive*
G04 Rotation:  0*
G04 FullContactRelief:  No*
G04 UndefLineWidth:     6.00*
G04 ================== end FILE IDENTIFICATION RECORD ====================*
%FSLAX25Y25*MOIN*%
%IR0*IPPOS*OFA0.00000B0.00000*MIA0B0*SFA1.00000B1.00000*%
%ADD41O,.052X.103*%
%ADD11C,.02*%
%ADD13C,.03*%
%ADD53C,.041*%
%ADD40C,.042*%
%ADD39C,.052*%
%ADD42C,.044*%
%ADD27C,.054*%
%ADD19C,.048*%
%ADD14C,.039*%
%ADD52C,.085*%
%AMMACRO56*
4,1,8,.078,-.0425,
.078,.0425,
-.078,.0425,
-.078,-.0425,
-.0236,-.0425,
-.0236,-.0145,
.0236,-.0145,
.0236,-.0425,
.078,-.0425,
0.0*
%
%ADD56MACRO56*%
%ADD44R,.044X.044*%
%ADD30R,.054X.054*%
%ADD57C,.0395*%
%ADD12R,.048X.048*%
%ADD58C,.0785*%
%AMMACRO37*
4,1,28,-.00748,-.00052,
-.00984,-.00052,
-.00984,-.00603,
-.009782,-.006705,
-.009607,-.007359,
-.009321,-.007974,
-.008933,-.008529,
-.008455,-.009009,
-.0079,-.009398,
-.007286,-.009685,
-.006632,-.009861,
-.005957,-.00992,
-.00591,-.00992,
.00591,-.00992,
.006585,-.009869,
.007242,-.009701,
.007859,-.009421,
.008418,-.009039,
.008903,-.008565,
.009297,-.008015,
.009591,-.007404,
.009773,-.006751,
.00984,-.006077,
.00984,-.00603,
.00984,-.00052,
.00748,-.00052,
.00748,.00991,
-.00748,.00991,
-.00748,-.00052,
0.0*
%
%ADD37MACRO37*%
%AMMACRO16*
4,1,28,-.00052,.00748,
-.00052,.00984,
-.00603,.00984,
-.006705,.009782,
-.007359,.009607,
-.007974,.009321,
-.008529,.008933,
-.009009,.008455,
-.009398,.0079,
-.009685,.007286,
-.009861,.006632,
-.00992,.005957,
-.00992,.00591,
-.00992,-.00591,
-.009869,-.006585,
-.009701,-.007242,
-.009421,-.007859,
-.009039,-.008418,
-.008565,-.008903,
-.008015,-.009297,
-.007404,-.009591,
-.006751,-.009773,
-.006077,-.00984,
-.00603,-.00984,
-.00052,-.00984,
-.00052,-.00748,
.00991,-.00748,
.00991,.00748,
-.00052,.00748,
0.0*
%
%ADD16MACRO16*%
%AMMACRO36*
4,1,28,-.00748,.00051,
-.00984,.00051,
-.00984,.00602,
-.009782,.006695,
-.009607,.007349,
-.009321,.007964,
-.008933,.008519,
-.008455,.008998,
-.0079,.009388,
-.007287,.009675,
-.006632,.009851,
-.005958,.00991,
-.00591,.00991,
.00591,.00991,
.006585,.009859,
.007242,.009691,
.007859,.009411,
.008418,.009029,
.008903,.008555,
.009297,.008005,
.00959,.007394,
.009773,.006742,
.00984,.006068,
.00984,.00602,
.00984,.00051,
.00748,.00051,
.00748,-.00992,
-.00748,-.00992,
-.00748,.00051,
0.0*
%
%ADD36MACRO36*%
%AMMACRO15*
4,1,28,.00051,.00748,
.00051,.00984,
.00602,.00984,
.006695,.009782,
.007349,.009607,
.007964,.009321,
.008519,.008933,
.008998,.008455,
.009388,.0079,
.009675,.007287,
.009851,.006632,
.00991,.005958,
.00991,.00591,
.00991,-.00591,
.009859,-.006585,
.009691,-.007242,
.009411,-.007859,
.009029,-.008418,
.008555,-.008903,
.008005,-.009297,
.007394,-.00959,
.006742,-.009773,
.006068,-.00984,
.00602,-.00984,
.00051,-.00984,
.00051,-.00748,
-.00992,-.00748,
-.00992,.00748,
.00051,.00748,
0.0*
%
%ADD15MACRO15*%
%ADD55R,.012X.02*%
%ADD51R,.04X.05*%
%ADD50R,.02X.018*%
%ADD21R,.032X.024*%
%ADD47R,.052X.024*%
%ADD35R,.04X.028*%
%ADD49R,.014X.036*%
%ADD45R,.028X.04*%
%ADD38R,.015X.053*%
%ADD29R,.017X.024*%
%ADD28R,.056X.04*%
%ADD24R,.054X.024*%
%ADD22R,.032X.028*%
%ADD46R,.028X.024*%
%ADD25R,.054X.016*%
%ADD48R,.038X.024*%
%ADD43O,.052X.075*%
%ADD32R,.024X.028*%
%ADD31R,.054X.044*%
%ADD23R,.056X.024*%
%ADD10C,.125*%
%ADD26C,.119*%
%ADD20C,.158*%
%AMMACRO54*
4,1,8,-.078,.0425,
-.078,-.0425,
.078,-.0425,
.078,.0425,
.0236,.0425,
.0236,.0145,
-.0236,.0145,
-.0236,.0425,
-.078,.0425,
0.0*
%
%ADD54MACRO54*%
%AMMACRO34*
4,1,28,.00748,.00052,
.00984,.00052,
.00984,.00603,
.009782,.006705,
.009607,.007359,
.009321,.007974,
.008933,.008529,
.008455,.009009,
.0079,.009398,
.007286,.009685,
.006632,.009861,
.005957,.00992,
.00591,.00992,
-.00591,.00992,
-.006585,.009869,
-.007242,.009701,
-.007859,.009421,
-.008418,.009039,
-.008903,.008565,
-.009297,.008015,
-.009591,.007404,
-.009773,.006751,
-.00984,.006077,
-.00984,.00603,
-.00984,.00052,
-.00748,.00052,
-.00748,-.00991,
.00748,-.00991,
.00748,.00052,
0.0*
%
%ADD34MACRO34*%
%AMMACRO18*
4,1,28,.00052,-.00748,
.00052,-.00984,
.00603,-.00984,
.006705,-.009782,
.007359,-.009607,
.007974,-.009321,
.008529,-.008933,
.009009,-.008455,
.009398,-.0079,
.009685,-.007286,
.009861,-.006632,
.00992,-.005957,
.00992,-.00591,
.00992,.00591,
.009869,.006585,
.009701,.007242,
.009421,.007859,
.009039,.008418,
.008565,.008903,
.008015,.009297,
.007404,.009591,
.006751,.009773,
.006077,.00984,
.00603,.00984,
.00052,.00984,
.00052,.00748,
-.00991,.00748,
-.00991,-.00748,
.00052,-.00748,
0.0*
%
%ADD18MACRO18*%
%AMMACRO33*
4,1,28,.00748,-.00051,
.00984,-.00051,
.00984,-.00602,
.009782,-.006695,
.009607,-.007349,
.009321,-.007964,
.008933,-.008519,
.008455,-.008998,
.0079,-.009388,
.007287,-.009675,
.006632,-.009851,
.005958,-.00991,
.00591,-.00991,
-.00591,-.00991,
-.006585,-.009859,
-.007242,-.009691,
-.007859,-.009411,
-.008418,-.009029,
-.008903,-.008555,
-.009297,-.008005,
-.00959,-.007394,
-.009773,-.006742,
-.00984,-.006068,
-.00984,-.00602,
-.00984,-.00051,
-.00748,-.00051,
-.00748,.00992,
.00748,.00992,
.00748,-.00051,
0.0*
%
%ADD33MACRO33*%
%AMMACRO17*
4,1,28,-.00051,-.00748,
-.00051,-.00984,
-.00602,-.00984,
-.006695,-.009782,
-.007349,-.009607,
-.007964,-.009321,
-.008519,-.008933,
-.008998,-.008455,
-.009388,-.0079,
-.009675,-.007287,
-.009851,-.006632,
-.00991,-.005958,
-.00991,-.00591,
-.00991,.00591,
-.009859,.006585,
-.009691,.007242,
-.009411,.007859,
-.009029,.008418,
-.008555,.008903,
-.008005,.009297,
-.007394,.00959,
-.006742,.009773,
-.006068,.00984,
-.00602,.00984,
-.00051,.00984,
-.00051,.00748,
.00992,.00748,
.00992,-.00748,
-.00051,-.00748,
0.0*
%
%ADD17MACRO17*%
%ADD59C,.015*%
%ADD60C,.018*%
%ADD61C,.028*%
%ADD62C,.006*%
%ADD63C,.0074*%
%ADD64C,.0058*%
%ADD65C,.1982*%
G75*
%LPD*%
G75*
G36*
G01X150834Y15521D02*
G03X151437Y15846I-14642J27888D01*
G01X152724D01*
Y7874D01*
G02X146850Y2000I-5874J0D01*
G01X7874D01*
G02X2000Y7874I0J5874D01*
G01Y13063D01*
G02X2200Y13263I200J0D01*
G01X3797D01*
G02X3997Y13063I1J-199D01*
G01Y7874D01*
G03X7874Y3997I3877J0D01*
G01X146850D01*
G03X150727Y7874I0J3877D01*
G01Y15344D01*
G02X150834Y15521I200J0D01*
G37*
G36*
G01X43701Y58661D02*
G03I-19685J0D01*
G37*
G36*
G01X2000Y86086D02*
Y248769D01*
G02X2139Y248959I200J0D01*
G01X2564Y249096D01*
X2687Y249055D01*
X2725Y249001D01*
G03X3952Y247397I25619J18326D01*
G02X3997Y247270I-155J-126D01*
G01Y181999D01*
Y132637D01*
Y87241D01*
G02X3949Y87110I-200J-1D01*
G03X3191Y86086I6234J-5407D01*
G01X2000D01*
G37*
G36*
G01X10236Y293229D02*
G02X41732I15748J0D01*
G01Y279449D01*
G02X10236I-15748J0D01*
G01Y293229D01*
G37*
G36*
G01X58464Y337173D02*
X113583D01*
G02X119457Y331299I0J-5874D01*
G01Y322835D01*
G03X129331Y312961I9874J0D01*
G01X142520D01*
G02X148394Y307087I0J-5874D01*
G01Y306865D01*
G02X148194Y306665I-200J0D01*
G01X148140D01*
X148094Y306692D01*
G03X146451Y307582I-15818J-27239D01*
G01X146344Y307727D01*
G03X142520Y310963I-3824J-641D01*
G01X129331D01*
G02X117459Y322835I0J11872D01*
G01Y331299D01*
G03X113678Y335174I-3876J0D01*
G01X113550Y335302D01*
X60914D01*
X59848D01*
X59477D01*
X59350Y335175D01*
X58812D01*
X58810D01*
X58464D01*
G03X54587Y331299I0J-3877D01*
G01Y322833D01*
G02X42716Y310963I-11871J1D01*
G01X12205D01*
G03X8329Y307087I0J-3876D01*
G01Y291736D01*
G02X8257Y291582I-200J0D01*
G03X7002Y290486I20084J-24264D01*
G01X6958Y290445D01*
X6842Y290426D01*
X6451Y290598D01*
G02X6331Y290781I80J183D01*
G01Y307087D01*
G02X12205Y312961I5874J0D01*
G01X42716D01*
G03X52590Y322835I0J9874D01*
G01Y331299D01*
G02X58464Y337173I5874J0D01*
G37*
G36*
G01X104000Y7500D02*
X102500Y6000D01*
X80000D01*
X52000D01*
X50000Y8000D01*
Y18500D01*
X52000Y20500D01*
X81000D01*
X83250Y22750D01*
Y35750D01*
X85500Y38000D01*
X102000D01*
X104000Y36000D01*
Y7500D01*
G37*
G36*
G01X55083Y115500D02*
X79417D01*
G02X79559Y115441I0J-200D01*
G01X80441Y114559D01*
G02X80500Y114417I-141J-142D01*
G01Y103083D01*
G02X80441Y102941I-200J0D01*
G01X79559Y102059D01*
G02X79417Y102000I-142J141D01*
G01X77583D01*
G03X77441Y101941I0J-200D01*
G01X76559Y101059D01*
G03X76500Y100917I141J-142D01*
G01Y100174D01*
X76488Y100127D01*
X76477Y100106D01*
G03X76204Y99000I2098J-1105D01*
G01Y97786D01*
G02X76145Y97645I-200J1D01*
G01X76059Y97559D01*
G02X75917Y97500I-142J141D01*
G01X70083D01*
G02X69941Y97559I0J200D01*
G01X69855Y97645D01*
G02X69796Y97786I141J142D01*
G01Y99000D01*
G03X69523Y100106I-2371J1D01*
G02X69500Y100199I177J93D01*
G01Y101417D01*
G03X69441Y101559I-200J0D01*
G01X69059Y101941D01*
G03X68917Y102000I-142J-141D01*
G01X66583D01*
G03X66441Y101941I0J-200D01*
G01X64059Y99559D01*
G02X63917Y99500I-142J141D01*
G01X58583D01*
G02X58441Y99559I0J200D01*
G01X57559Y100441D01*
G02X57500Y100583I141J142D01*
G01Y103917D01*
G03X57441Y104059I-200J0D01*
G01X53559Y107941D01*
G02X53500Y108083I141J142D01*
G01Y113917D01*
G02X53559Y114059I200J0D01*
G01X54941Y115441D01*
G02X55083Y115500I142J-141D01*
G37*
G36*
G01X60500Y267000D02*
X59200D01*
X57000Y264800D01*
Y263000D01*
X55700Y261700D01*
Y259400D01*
X55900Y259200D01*
X60700D01*
X61000Y259500D01*
Y266500D01*
X60500Y267000D01*
G37*
G36*
G01X63207Y55000D02*
G03I-707J0D01*
G37*
G36*
G01X66707Y118000D02*
G03I-707J0D01*
G37*
G36*
G01X70707Y138500D02*
G03I-707J0D01*
G37*
G36*
G01X71207Y177500D02*
G03I-707J0D01*
G37*
G36*
G01X72500Y264500D02*
X74500Y262500D01*
Y258000D01*
X75500Y257000D01*
X77000D01*
X77500Y257500D01*
Y259000D01*
X78000Y259500D01*
Y263500D01*
X72500Y269000D01*
Y271000D01*
X72000Y271500D01*
X71500D01*
X71000Y271000D01*
Y268500D01*
X72500Y267000D01*
Y264500D01*
G37*
G36*
G01X66600Y277128D02*
X67600D01*
G02X67800Y276928I0J-200D01*
G01Y256883D01*
G02X67741Y256741I-200J0D01*
G01X67559Y256559D01*
G02X67417Y256500I-142J141D01*
G01X62583D01*
G02X62441Y256559I0J200D01*
G01X62059Y256941D01*
G02X62000Y257083I141J142D01*
G01Y259084D01*
X62002Y259085D01*
Y265943D01*
G02X62060Y266084I200J0D01*
G01X66002Y270027D01*
G03X66516Y271265I-1237J1239D01*
G01Y274803D01*
G03X66412Y275397I-1752J-1D01*
G01X66400Y275429D01*
Y276928D01*
G02X66600Y277128I200J0D01*
G37*
G36*
G01X69002D02*
X70000D01*
G02X70200Y276928I0J-200D01*
G01Y275389D01*
X70190Y275358D01*
G03X70100Y274803I1661J-554D01*
G01Y271599D01*
G02X70041Y271457I-200J0D01*
G01X70029Y271445D01*
X69998Y271372D01*
Y268168D01*
G03X70057Y268027I200J1D01*
G01X71440Y266644D01*
G02X71498Y266502I-142J-141D01*
G01Y264085D01*
X71500Y264084D01*
Y264083D01*
G03X71559Y263941I200J0D01*
G01X73440Y262060D01*
G02X73498Y261919I-142J-141D01*
G01Y257585D01*
X73500Y257584D01*
Y257083D01*
G02X73441Y256941I-200J0D01*
G01X73059Y256559D01*
G02X72917Y256500I-142J141D01*
G01X69083D01*
G02X68941Y256559I0J200D01*
G01X68860Y256640D01*
G02X68802Y256781I142J141D01*
G01Y276928D01*
G02X69002Y277128I200J0D01*
G37*
G36*
G01X85207Y95000D02*
G03I-707J0D01*
G37*
G36*
G01X82207Y126500D02*
G03I-707J0D01*
G37*
G36*
G01X95207Y129000D02*
G03I-707J0D01*
G37*
G36*
G01X120473Y57205D02*
G02X151969I15748J0D01*
G01Y43425D01*
G02X120473I-15748J0D01*
G01Y57205D01*
G37*
G36*
G01X118083Y137500D02*
X125917D01*
G02X126059Y137441I0J-200D01*
G01X126441Y137059D01*
G02X126500Y136917I-141J-142D01*
G01Y125583D01*
G02X126441Y125441I-200J0D01*
G01X126059Y125059D01*
G02X125917Y125000I-142J141D01*
G01X117583D01*
G02X117441Y125059I0J200D01*
G01X117060Y125440D01*
G02X117002Y125581I142J141D01*
G01Y136419D01*
G02X117060Y136560I200J0D01*
G01X117941Y137441D01*
G02X118083Y137500I142J-141D01*
G37*
G36*
G01X111083Y152000D02*
X116417D01*
G02X116559Y151941I0J-200D01*
G01X116941Y151559D01*
G02X117000Y151417I-141J-142D01*
G01Y138583D01*
G02X116941Y138441I-200J0D01*
G01X116059Y137559D01*
G03X116000Y137417I141J-142D01*
G01Y123583D01*
G03X116059Y123441I200J0D01*
G01X116441Y123059D01*
G03X116583Y123000I142J141D01*
G01X123417D01*
G02X123559Y122941I0J-200D01*
G01X123941Y122559D01*
G02X124000Y122417I-141J-142D01*
G01Y119083D01*
G02X123941Y118941I-200J0D01*
G01X123559Y118559D01*
G02X123417Y118500I-142J141D01*
G01X113308D01*
G02X113166Y118559I0J200D01*
G01X111795Y119930D01*
G02X111736Y120062I141J142D01*
G01X110500Y145792D01*
Y151417D01*
G02X110559Y151559I200J0D01*
G01X110941Y151941D01*
G02X111083Y152000I142J-141D01*
G37*
G36*
G01X148819Y247543D02*
G03I-19685J0D01*
G37*
G36*
G01X142583Y137500D02*
X148917D01*
G02X149059Y137441I0J-200D01*
G01X149441Y137059D01*
G02X149500Y136917I-141J-142D01*
G01Y111083D01*
G02X149441Y110941I-200J0D01*
G01X149059Y110559D01*
G02X148917Y110500I-142J141D01*
G01X142583D01*
G02X142441Y110559I0J200D01*
G01X142060Y110940D01*
G02X142002Y111081I142J141D01*
G01Y136919D01*
G02X142060Y137060I200J0D01*
G01X142441Y137441D01*
G02X142583Y137500I142J-141D01*
G37*
G36*
G01X133941Y110559D02*
X133559Y110941D01*
G02X133500Y111083I141J142D01*
G01Y117917D01*
G03X133441Y118059I-200J0D01*
G01X133059Y118441D01*
G03X132917Y118500I-142J-141D01*
G01X128583D01*
G02X128441Y118559I0J200D01*
G01X128059Y118941D01*
G02X128000Y119083I141J142D01*
G01Y136917D01*
G02X128059Y137059I200J0D01*
G01X128441Y137441D01*
G02X128583Y137500I142J-141D01*
G01X140417D01*
G02X140559Y137441I0J-200D01*
G01X140941Y137059D01*
G02X141000Y136917I-141J-142D01*
G01Y111083D01*
G02X140941Y110941I-200J0D01*
G01X140559Y110559D01*
G02X140417Y110500I-142J141D01*
G01X134083D01*
G02X133941Y110559I0J200D01*
G37*
G36*
G01X150809Y253975D02*
G03X151697Y254645I-18524J25475D01*
G01X151877D01*
X151890Y254632D01*
X152604D01*
X152724Y254512D01*
Y71204D01*
X151070D01*
G03X150834Y71329I-14861J-27772D01*
G02X150727Y71506I93J177D01*
G01Y253813D01*
G02X150809Y253975I200J1D01*
G37*
%LPC*%
G75*
G36*
G01X16765Y285779D02*
G02X35203Y285778I9219J7449D01*
G03X33900Y282093I4560J-3685D01*
G01Y279449D01*
G02X18068I-7916J0D01*
G01Y282093D01*
G03X16765Y285779I-5865J0D01*
G37*
G36*
G01X127002Y49755D02*
G02X145440Y49754I9219J7449D01*
G03X144137Y46069I4560J-3685D01*
G01Y43425D01*
G02X128305I-7916J0D01*
G01Y46069D01*
G03X127002Y49755I-5865J0D01*
G37*
G54D65*
X24016Y58661D03*
X129134Y247543D03*
%LPD*%
G75*
G54D10*
X-58189Y19685D03*
Y666535D03*
X14000Y255500D03*
X60989Y131906D03*
X134016Y147928D03*
X372440Y19685D03*
Y666535D03*
G54D20*
X24016Y58661D03*
X129134Y247543D03*
G54D11*
G01X28567Y186000D02*
X33000D01*
G01X106970Y65827D02*
X112665D01*
X120511Y73673D01*
Y75644D01*
G01X106970Y68327D02*
Y65827D01*
X5192Y3841D03*
X10315Y13000D03*
X3004Y90860D03*
Y106468D03*
X8000Y99500D03*
Y110500D03*
X16000Y98441D03*
Y109441D03*
X8000Y103500D03*
Y114500D03*
X3004Y126468D03*
Y146468D03*
Y166468D03*
X11500Y200000D03*
Y192000D03*
Y184000D03*
X3004Y186468D03*
X11500Y196000D03*
Y188000D03*
X3004Y206468D03*
X11500Y204000D03*
X3004Y226468D03*
Y246468D03*
X13984Y279449D03*
X7348Y302588D03*
X7337Y292952D03*
X27028Y3019D03*
X33000Y186000D03*
X19500Y221500D03*
Y213500D03*
Y209500D03*
Y217500D03*
Y229500D03*
Y237500D03*
Y225500D03*
Y233500D03*
Y241500D03*
Y245500D03*
X34469Y270964D03*
X25984Y267449D03*
X17499Y270964D03*
X35701Y311937D03*
X16801Y311946D03*
X46184Y3014D03*
X59586Y40000D03*
X59500Y55000D03*
X48941Y89500D03*
X52000Y81000D03*
X59500Y95000D03*
X42400Y86500D03*
X54059Y102500D03*
X41500Y103500D03*
X41038Y112537D03*
X41000Y213532D03*
X59075Y204000D03*
X55925D03*
X56500Y261000D03*
X57800Y263900D03*
X37984Y279449D03*
X51404Y316245D03*
X53595Y331234D03*
X60867Y3014D03*
X81000Y8000D03*
X63600Y34192D03*
X72555Y46921D03*
X64500Y63500D03*
X66925Y70000D03*
X70075Y64500D03*
X68720Y54000D03*
X77382Y58000D03*
X62500Y55000D03*
X81729Y77772D03*
X77453Y77500D03*
X73000Y91000D03*
Y87000D03*
X65000Y73500D03*
X73000Y95000D03*
X78500Y110000D03*
Y112500D03*
X75425Y102000D03*
X66000Y118000D03*
X59500Y117960D03*
X76000Y123000D03*
Y126500D03*
X78340Y136000D03*
X70000Y138500D03*
X70500Y177500D03*
X67000D03*
X64075Y200000D03*
X66500Y181500D03*
Y185500D03*
Y189500D03*
Y193500D03*
X76500Y227500D03*
X68500Y231500D03*
X76500Y239500D03*
Y235500D03*
Y231500D03*
X76400Y258000D03*
X69075Y247000D03*
X75700Y263900D03*
X64000Y258000D03*
X66500D03*
X65925Y247000D03*
X72500Y258000D03*
X70000D03*
X78937Y270653D03*
X75394Y288205D03*
X64764D03*
X71851D03*
X80119D03*
X68308D03*
X68968Y336145D03*
X80697Y3016D03*
X98502D03*
X99500Y9000D03*
X91000Y18500D03*
X99000Y65500D03*
X84500Y76500D03*
X81000Y91000D03*
X84500Y95000D03*
X81000D03*
X81500Y126500D03*
X94500Y129000D03*
X83500Y133000D03*
Y129500D03*
X88500Y123500D03*
X92500Y126000D03*
X80310Y138735D03*
X93111Y288205D03*
X100197Y270653D03*
X86024D03*
X93111D03*
X84843Y288205D03*
X101378D03*
X96654D03*
X89567D03*
X83076Y336146D03*
X118500Y6716D03*
X117186Y3014D03*
X113181Y31701D03*
X106954Y21716D03*
X111965Y11716D03*
X109812Y16716D03*
X122130Y30217D03*
X107318Y63176D03*
X106970Y65827D03*
Y68327D03*
X118000Y116500D03*
X120500Y136500D03*
Y129500D03*
Y133000D03*
Y126000D03*
X112000Y147000D03*
Y150500D03*
X115000Y147000D03*
Y150500D03*
X107284Y270653D03*
X106103Y288205D03*
X118455Y323862D03*
X116870Y334863D03*
X103076Y336146D03*
X136936Y3035D03*
X132000Y10500D03*
X139500D03*
X127500Y6716D03*
X124221Y43425D03*
X127736Y34940D03*
X136221Y31425D03*
X144706Y34940D03*
X128385Y80000D03*
X137000Y84500D03*
Y88000D03*
Y92000D03*
X134500Y136500D03*
Y133000D03*
Y129500D03*
Y126000D03*
Y122500D03*
Y119000D03*
X133500Y160000D03*
X132500Y185000D03*
X129715Y311960D03*
X150330Y4601D03*
X151688Y13776D03*
X148221Y43425D03*
X151706Y72716D03*
X151683Y90942D03*
X148500Y88000D03*
Y80000D03*
Y76000D03*
Y84000D03*
Y92000D03*
X151684Y112798D03*
X148500Y96000D03*
Y112000D03*
Y104000D03*
Y108000D03*
Y100000D03*
X151684Y132682D03*
X148500Y136500D03*
Y133000D03*
Y129500D03*
Y126000D03*
Y122500D03*
Y119000D03*
Y115500D03*
X151683Y151482D03*
X151705Y172913D03*
X151663Y192669D03*
X151662Y212615D03*
X151704Y232645D03*
X151705Y252655D03*
X144561Y311483D03*
X350990Y434698D03*
X341684Y431703D03*
X339169Y431688D03*
X349698D03*
X352213Y431703D03*
X344419Y428405D03*
X346934Y428420D03*
X352199Y428435D03*
X349684Y428420D03*
X341670Y428405D03*
X339155Y428420D03*
X340461Y434698D03*
X350539Y607802D03*
X351845Y614080D03*
X349330Y614095D03*
X338801Y614065D03*
X341316Y614080D03*
X338787Y610797D03*
X341302Y610812D03*
X344066Y614080D03*
X346581Y614095D03*
X351831Y610812D03*
X349316Y610797D03*
X340010Y607802D03*
X371184Y327889D03*
X368669Y327874D03*
X379198D03*
X373919Y324591D03*
X376434Y324606D03*
X379184D03*
X371170Y324591D03*
X368655Y324606D03*
X369961Y330884D03*
X369510Y607802D03*
X378816Y610797D03*
X370802Y610812D03*
X368287Y610797D03*
X376081Y614095D03*
X373566Y614080D03*
X368301Y614065D03*
X370816Y614080D03*
X378830Y614095D03*
X381713Y327889D03*
X381699Y324621D03*
X380490Y330884D03*
X381331Y610812D03*
X381345Y614080D03*
X380039Y607802D03*
G54D21*
X25650Y101000D03*
X19350Y98441D03*
Y103559D03*
X25650Y112000D03*
X19350Y109441D03*
Y114559D03*
G54D12*
X10315Y20079D03*
X33937D03*
G54D30*
X77480Y26299D03*
G54D31*
X76755Y39441D03*
Y46921D03*
G54D22*
X36600Y98500D03*
Y109500D03*
X42400Y98500D03*
Y109500D03*
X63600Y37100D03*
X69400D03*
X70600Y261000D03*
X76400D03*
X65400D03*
X59600D03*
G54D40*
X61516Y326772D03*
Y314961D03*
X110532Y326772D03*
Y314961D03*
G54D13*
X13553Y48198D03*
Y69124D03*
X9218Y58661D03*
X16000Y119500D03*
X34479Y48198D03*
X24016Y43863D03*
X34479Y69124D03*
X24016Y73459D03*
X31000Y112000D03*
Y101000D03*
X22000Y190000D03*
Y201000D03*
Y196000D03*
X30000Y223500D03*
Y218500D03*
Y213500D03*
Y236500D03*
Y241500D03*
X38814Y58661D03*
X42400Y93000D03*
X51500Y105000D03*
X44500Y104000D03*
X56000Y186000D03*
Y196500D03*
Y191500D03*
X50500Y249000D03*
X79000Y223500D03*
X66000Y224500D03*
X81500Y243001D03*
X81000Y235500D03*
X66000Y229500D03*
Y239500D03*
Y234500D03*
X61256Y254000D03*
X72500Y250000D03*
X89000Y128000D03*
X82500Y262000D03*
X88500D03*
X83568Y256068D03*
X118671Y237080D03*
Y258006D03*
X114336Y247543D03*
X137500Y100000D03*
X133000Y104000D03*
X137500Y107000D03*
X139597Y237080D03*
X129134Y232745D03*
Y262341D03*
X139597Y258006D03*
X143932Y247543D03*
G54D23*
X28567Y186000D03*
Y191000D03*
Y196000D03*
Y201000D03*
X49433Y196000D03*
Y191000D03*
Y186000D03*
Y201000D03*
G54D32*
X78240Y72563D03*
X70760D03*
Y80437D03*
G54D50*
X126121Y92117D03*
X122775D03*
X126121Y95267D03*
X122775D03*
G54D14*
X11489Y85883D03*
X51000Y301000D03*
X105000Y234500D03*
G54D41*
X87756Y47244D03*
X109095Y89370D03*
G54D60*
G01X10315Y20079D02*
Y13000D01*
G01X10425Y99500D02*
X8000D01*
G01X10425Y110500D02*
X8000D01*
G01X10425Y103500D02*
X8000D01*
G01X10425Y114500D02*
X8000D01*
G01X13925Y184000D02*
X11500D01*
G01X13925Y192000D02*
X11500D01*
G01X13925Y200000D02*
X11500D01*
G01X13925Y188000D02*
X11500D01*
G01X13925Y196000D02*
X11500D01*
G01X13925Y204000D02*
X11500D01*
G01X16000Y98441D02*
X19350D01*
G01X16000Y109441D02*
X19350D01*
G01X21925Y221500D02*
X19500D01*
G01X21925Y213500D02*
X19500D01*
G01X41000Y213532D02*
X36484D01*
G01X21925Y217500D02*
X19500D01*
G01X21925Y209500D02*
X19500D01*
G01X21925Y229500D02*
X19500D01*
G01X21925Y237500D02*
X19500D01*
G01Y225500D02*
X21925D01*
G01X19500Y233500D02*
X21925D01*
G01Y241500D02*
X19500D01*
G01X21925Y245500D02*
X19500D01*
G01X48941Y92260D02*
Y89500D01*
G01D02*
X50941Y87500D01*
X51425D01*
G01X52000Y81000D02*
X51425Y81575D01*
Y83500D01*
G01X54059Y102500D02*
Y99740D01*
G01X39075Y103500D02*
X41500D01*
G01X39075Y114500D02*
X41038Y112537D01*
G01X55925Y201500D02*
Y204000D01*
G01X49433Y201000D02*
X53001D01*
X53501Y201500D01*
X55925D01*
G01X59600Y261000D02*
X56500D01*
G01X59586Y43608D02*
Y40000D01*
G01X76755Y46921D02*
X72555D01*
G01X63600Y37100D02*
Y34192D01*
G01X77382Y61707D02*
Y58000D01*
G01X77453Y77500D02*
Y80437D01*
G01X64075Y177500D02*
X67000D01*
G01X64075Y197500D02*
Y200000D01*
G01Y189500D02*
X66500D01*
G01X64075Y193500D02*
X66500D01*
G01X59075Y201500D02*
Y204000D01*
G01X74075Y227500D02*
X76500D01*
G01X65925Y244500D02*
X64001D01*
X61969Y242468D01*
X59516D01*
G01X74075Y231500D02*
X76500D01*
G01X69075Y244500D02*
Y247000D01*
G01X76400Y261000D02*
Y258000D01*
G01X65925Y247000D02*
Y244500D01*
G01X109095Y89370D02*
Y96889D01*
X98437Y107547D01*
G01X118500Y6716D02*
X122983D01*
G01X120763Y27211D02*
X117671D01*
X113181Y31701D01*
G01X122130Y30217D02*
X123913Y28434D01*
Y27211D01*
G01X121571Y116500D02*
X118000D01*
G01X143849Y21716D02*
X129408D01*
X123913Y27211D01*
G01X128385Y76431D02*
Y80000D01*
G01X148500Y88000D02*
X146075D01*
G01X148500Y80000D02*
X146075D01*
G01Y92000D02*
X148500D01*
G01X146075Y84000D02*
X148500D01*
G01Y76000D02*
X146075D01*
G01Y104000D02*
X148500D01*
G01X146075Y96000D02*
X148500D01*
G54D33*
X59500Y57516D03*
X65000Y76016D03*
X59500Y97516D03*
X81500Y248016D03*
X85500D03*
G54D24*
X36484Y213532D03*
Y242468D03*
X59516Y213532D03*
Y242468D03*
G54D51*
X145000Y113500D03*
X138000D03*
X145000Y127500D03*
X138000D03*
X145000Y120500D03*
X138000D03*
X124000Y134500D03*
X131000D03*
X124000Y127500D03*
X131000D03*
X145000Y134500D03*
X138000D03*
G54D15*
X13484Y114500D03*
Y103500D03*
X16984Y196000D03*
Y188000D03*
Y200000D03*
Y204000D03*
X24984Y217500D03*
Y209500D03*
Y225500D03*
X54484Y83500D03*
X69984Y67500D03*
X78484Y91000D03*
Y87000D03*
X70484Y91000D03*
X78484Y95000D03*
Y99000D03*
X70484Y95000D03*
X63984Y197500D03*
X73984Y219500D03*
X58984Y201500D03*
X73984Y227500D03*
Y231500D03*
Y223500D03*
X68984Y244500D03*
X73484Y265500D03*
X93984Y120000D03*
X117984Y126000D03*
Y130000D03*
X145984Y88000D03*
Y80000D03*
Y104000D03*
Y96000D03*
G54D42*
X101969Y52480D03*
Y68228D03*
Y60354D03*
X94882Y54449D03*
Y64291D03*
Y72165D03*
X101969Y83976D03*
Y76102D03*
G54D61*
G01X78240Y72563D02*
X85437D01*
X94882Y82008D01*
G01D02*
X97000Y84126D01*
Y97407D01*
X90563Y103844D01*
Y106760D01*
G54D34*
X59500Y60483D03*
X65000Y78983D03*
X59500Y100483D03*
X81500Y250983D03*
X85500D03*
G54D43*
X87756Y89370D03*
X109095Y47244D03*
G54D25*
X36484Y216484D03*
Y219043D03*
Y221602D03*
Y224161D03*
Y226720D03*
Y229280D03*
Y231839D03*
Y234398D03*
Y236957D03*
Y239516D03*
X59516Y221602D03*
Y219043D03*
Y216484D03*
Y239516D03*
Y236957D03*
Y234398D03*
Y231839D03*
Y229280D03*
Y226720D03*
Y224161D03*
G54D16*
X10517Y114500D03*
Y103500D03*
X14017Y196000D03*
Y188000D03*
Y200000D03*
Y204000D03*
X22017Y217500D03*
Y209500D03*
Y225500D03*
X51517Y83500D03*
X56017Y201500D03*
X67017Y67500D03*
X75517Y91000D03*
Y87000D03*
X67517Y91000D03*
X75517Y95000D03*
Y99000D03*
X67517Y95000D03*
X61017Y197500D03*
X71017Y219500D03*
Y227500D03*
Y231500D03*
Y223500D03*
X66017Y244500D03*
X70517Y265500D03*
X91017Y120000D03*
X115017Y126000D03*
Y130000D03*
X143017Y88000D03*
Y80000D03*
Y104000D03*
Y96000D03*
G54D52*
X339937Y104912D03*
X344937Y91728D03*
X349937Y104912D03*
X352033Y234525D03*
X342033D03*
X347033Y247709D03*
G54D62*
G01X-117168Y-317735D02*
Y-322735D01*
G01X-118625Y-317735D02*
X-115711D01*
G01X-110801Y-322735D02*
X-113335D01*
Y-317735D01*
X-110801D01*
G01X-111815Y-320152D02*
X-113335D01*
G01X-108235Y-317735D02*
Y-322735D01*
X-105701D01*
G01X-101868Y-322902D02*
X-101995Y-322818D01*
Y-322652D01*
X-101868Y-322568D01*
X-101741Y-322652D01*
Y-322818D01*
X-101868Y-322902D01*
G01Y-320652D02*
X-101995Y-320568D01*
Y-320402D01*
X-101868Y-320318D01*
X-101741Y-320402D01*
Y-320568D01*
X-101868Y-320652D01*
G01X-97085Y-324402D02*
X-97718Y-323568D01*
X-98035Y-322735D01*
Y-319402D01*
X-97718Y-318568D01*
X-97085Y-317735D01*
G01X-91668D02*
X-92175Y-317902D01*
X-92555Y-318318D01*
X-92808Y-318818D01*
X-92998Y-319485D01*
X-93061Y-320235D01*
X-92998Y-320985D01*
X-92808Y-321652D01*
X-92555Y-322152D01*
X-92175Y-322568D01*
X-91668Y-322735D01*
X-91161Y-322568D01*
X-90781Y-322152D01*
X-90528Y-321652D01*
X-90338Y-320985D01*
X-90275Y-320235D01*
X-90338Y-319485D01*
X-90528Y-318818D01*
X-90781Y-318318D01*
X-91161Y-317902D01*
X-91668Y-317735D01*
G01X-87961Y-321735D02*
X-87581Y-322318D01*
X-87075Y-322652D01*
X-86505Y-322735D01*
X-85998Y-322652D01*
X-85491Y-322235D01*
X-85175Y-321735D01*
X-85111Y-321235D01*
X-85238Y-320652D01*
X-85681Y-320235D01*
X-86125Y-320068D01*
X-86695D01*
G01X-86125D02*
X-85745Y-319818D01*
X-85428Y-319402D01*
X-85301Y-318902D01*
X-85428Y-318402D01*
X-85745Y-317985D01*
X-86315Y-317735D01*
X-86885Y-317818D01*
X-87455Y-318152D01*
G01X-81151Y-324402D02*
X-80518Y-323568D01*
X-80201Y-322735D01*
Y-319402D01*
X-80518Y-318568D01*
X-81151Y-317735D01*
G01X-77761Y-321735D02*
X-77381Y-322318D01*
X-76875Y-322652D01*
X-76305Y-322735D01*
X-75798Y-322652D01*
X-75291Y-322235D01*
X-74975Y-321735D01*
X-74911Y-321235D01*
X-75038Y-320652D01*
X-75481Y-320235D01*
X-75925Y-320068D01*
X-76495D01*
G01X-75925D02*
X-75545Y-319818D01*
X-75228Y-319402D01*
X-75101Y-318902D01*
X-75228Y-318402D01*
X-75545Y-317985D01*
X-76115Y-317735D01*
X-76685Y-317818D01*
X-77255Y-318152D01*
G01X-72471Y-318568D02*
X-72091Y-318068D01*
X-71648Y-317818D01*
X-71141Y-317735D01*
X-70508Y-317902D01*
X-70065Y-318318D01*
X-69938Y-318818D01*
X-70001Y-319318D01*
X-70255Y-319735D01*
X-71521Y-320568D01*
X-72091Y-321152D01*
X-72471Y-321985D01*
X-72598Y-322735D01*
X-69938D01*
G01X-66295D02*
X-66168Y-321652D01*
X-65978Y-320735D01*
X-65725Y-319902D01*
X-65408Y-318985D01*
X-64901Y-317735D01*
X-67435D01*
G01X-61891Y-321068D02*
X-60245D01*
G01X-57171Y-318568D02*
X-56791Y-318068D01*
X-56348Y-317818D01*
X-55841Y-317735D01*
X-55208Y-317902D01*
X-54765Y-318318D01*
X-54638Y-318818D01*
X-54701Y-319318D01*
X-54955Y-319735D01*
X-56221Y-320568D01*
X-56791Y-321152D01*
X-57171Y-321985D01*
X-57298Y-322735D01*
X-54638D01*
G01X-52261Y-321735D02*
X-51881Y-322318D01*
X-51375Y-322652D01*
X-50805Y-322735D01*
X-50298Y-322652D01*
X-49791Y-322235D01*
X-49475Y-321735D01*
X-49411Y-321235D01*
X-49538Y-320652D01*
X-49981Y-320235D01*
X-50425Y-320068D01*
X-50995D01*
G01X-50425D02*
X-50045Y-319818D01*
X-49728Y-319402D01*
X-49601Y-318902D01*
X-49728Y-318402D01*
X-50045Y-317985D01*
X-50615Y-317735D01*
X-51185Y-317818D01*
X-51755Y-318152D01*
G01X-45008Y-322735D02*
Y-317735D01*
X-47351Y-321318D01*
X-44185D01*
G01X-42061Y-321985D02*
X-41681Y-322402D01*
X-41238Y-322652D01*
X-40668Y-322735D01*
X-40098Y-322568D01*
X-39655Y-322235D01*
X-39338Y-321652D01*
X-39275Y-320985D01*
X-39401Y-320318D01*
X-39718Y-319902D01*
X-40161Y-319568D01*
X-40605Y-319485D01*
X-41048Y-319568D01*
X-41618Y-319902D01*
X-41428Y-317735D01*
X-39718D01*
G01X-31671Y-322735D02*
Y-317735D01*
X-29265D01*
G01X-30151Y-320152D02*
X-31671D01*
G01X-26951Y-322735D02*
X-25368Y-317735D01*
X-23785Y-322735D01*
G01X-24355Y-320985D02*
X-26381D01*
G01X-21598Y-322735D02*
X-18938Y-317735D01*
G01X-21598D02*
X-18938Y-322735D01*
G01X-15168Y-322902D02*
X-15295Y-322818D01*
Y-322652D01*
X-15168Y-322568D01*
X-15041Y-322652D01*
Y-322818D01*
X-15168Y-322902D01*
G01Y-320652D02*
X-15295Y-320568D01*
Y-320402D01*
X-15168Y-320318D01*
X-15041Y-320402D01*
Y-320568D01*
X-15168Y-320652D01*
G01X-10385Y-324402D02*
X-11018Y-323568D01*
X-11335Y-322735D01*
Y-319402D01*
X-11018Y-318568D01*
X-10385Y-317735D01*
G01X-4968D02*
X-5475Y-317902D01*
X-5855Y-318318D01*
X-6108Y-318818D01*
X-6298Y-319485D01*
X-6361Y-320235D01*
X-6298Y-320985D01*
X-6108Y-321652D01*
X-5855Y-322152D01*
X-5475Y-322568D01*
X-4968Y-322735D01*
X-4461Y-322568D01*
X-4081Y-322152D01*
X-3828Y-321652D01*
X-3638Y-320985D01*
X-3575Y-320235D01*
X-3638Y-319485D01*
X-3828Y-318818D01*
X-4081Y-318318D01*
X-4461Y-317902D01*
X-4968Y-317735D01*
G01X-1261Y-321735D02*
X-881Y-322318D01*
X-375Y-322652D01*
X195Y-322735D01*
X702Y-322652D01*
X1209Y-322235D01*
X1525Y-321735D01*
X1589Y-321235D01*
X1462Y-320652D01*
X1019Y-320235D01*
X575Y-320068D01*
X5D01*
G01X575D02*
X955Y-319818D01*
X1272Y-319402D01*
X1399Y-318902D01*
X1272Y-318402D01*
X955Y-317985D01*
X385Y-317735D01*
X-185Y-317818D01*
X-755Y-318152D01*
G01X5549Y-324402D02*
X6182Y-323568D01*
X6499Y-322735D01*
Y-319402D01*
X6182Y-318568D01*
X5549Y-317735D01*
G01X8939Y-321735D02*
X9319Y-322318D01*
X9825Y-322652D01*
X10395Y-322735D01*
X10902Y-322652D01*
X11409Y-322235D01*
X11725Y-321735D01*
X11789Y-321235D01*
X11662Y-320652D01*
X11219Y-320235D01*
X10775Y-320068D01*
X10205D01*
G01X10775D02*
X11155Y-319818D01*
X11472Y-319402D01*
X11599Y-318902D01*
X11472Y-318402D01*
X11155Y-317985D01*
X10585Y-317735D01*
X10015Y-317818D01*
X9445Y-318152D01*
G01X14355Y-322152D02*
X14799Y-322568D01*
X15305Y-322735D01*
X15812Y-322568D01*
X16255Y-322068D01*
X16572Y-321318D01*
X16699Y-320568D01*
Y-319652D01*
X16572Y-318902D01*
X16255Y-318235D01*
X15875Y-317902D01*
X15432Y-317735D01*
X14925Y-317902D01*
X14545Y-318235D01*
X14292Y-318735D01*
X14165Y-319402D01*
X14292Y-319985D01*
X14609Y-320568D01*
X14989Y-320902D01*
X15432Y-320985D01*
X15939Y-320818D01*
X16319Y-320402D01*
X16699Y-319652D01*
G01X20405Y-322735D02*
X20532Y-321652D01*
X20722Y-320735D01*
X20975Y-319902D01*
X21292Y-318985D01*
X21799Y-317735D01*
X19265D01*
G01X24809Y-321068D02*
X26455D01*
G01X29339Y-321735D02*
X29719Y-322318D01*
X30225Y-322652D01*
X30795Y-322735D01*
X31302Y-322652D01*
X31809Y-322235D01*
X32125Y-321735D01*
X32189Y-321235D01*
X32062Y-320652D01*
X31619Y-320235D01*
X31175Y-320068D01*
X30605D01*
G01X31175D02*
X31555Y-319818D01*
X31872Y-319402D01*
X31999Y-318902D01*
X31872Y-318402D01*
X31555Y-317985D01*
X30985Y-317735D01*
X30415Y-317818D01*
X29845Y-318152D01*
G01X34629Y-320652D02*
X35072Y-320068D01*
X35452Y-319735D01*
X35959Y-319568D01*
X36402Y-319735D01*
X36719Y-320068D01*
X36972Y-320568D01*
X37035Y-321152D01*
X36972Y-321652D01*
X36719Y-322152D01*
X36339Y-322568D01*
X35895Y-322735D01*
X35389Y-322568D01*
X34945Y-322068D01*
X34692Y-321318D01*
X34629Y-320485D01*
X34755Y-319402D01*
X34945Y-318818D01*
X35262Y-318235D01*
X35705Y-317818D01*
X36149Y-317735D01*
X36592Y-317902D01*
X36909Y-318318D01*
G01X40932Y-322735D02*
Y-317735D01*
X40172Y-318735D01*
G01Y-322735D02*
X41692D01*
G01X46792D02*
Y-317735D01*
X44449Y-321318D01*
X47615D01*
G01X-129168Y-252735D02*
Y-327735D01*
X370832D01*
Y-252735D01*
X-129168D01*
G01X65832D02*
Y-327735D01*
G01Y-302735D02*
X168832D01*
Y-277735D01*
G01X65832D02*
X168832D01*
G01X176339Y-312735D02*
Y-307735D01*
X177605D01*
X178112Y-307985D01*
X178492Y-308318D01*
X178809Y-308818D01*
X179062Y-309402D01*
X179125Y-310235D01*
X179062Y-311068D01*
X178809Y-311652D01*
X178492Y-312152D01*
X178112Y-312485D01*
X177605Y-312735D01*
X176339D01*
G01X181249D02*
X182832Y-307735D01*
X184415Y-312735D01*
G01X183845Y-310985D02*
X181819D01*
G01X187932Y-307735D02*
Y-312735D01*
G01X186475Y-307735D02*
X189389D01*
G01X194299Y-312735D02*
X191765D01*
Y-307735D01*
X194299D01*
G01X193285Y-310152D02*
X191765D01*
G01X198132Y-312902D02*
X198005Y-312818D01*
Y-312652D01*
X198132Y-312568D01*
X198259Y-312652D01*
Y-312818D01*
X198132Y-312902D01*
G01Y-310652D02*
X198005Y-310568D01*
Y-310402D01*
X198132Y-310318D01*
X198259Y-310402D01*
Y-310568D01*
X198132Y-310652D01*
G01X170832Y-252735D02*
Y-327735D01*
G01X168832Y-252735D02*
Y-327735D01*
G01X170832Y-302735D02*
X370832D01*
G01X176465Y-287735D02*
Y-282735D01*
X177985D01*
X178492Y-282985D01*
X178872Y-283568D01*
X178999Y-284235D01*
X178872Y-284902D01*
X178555Y-285402D01*
X177985Y-285652D01*
X176465D01*
G01X181692Y-287902D02*
X183972Y-282735D01*
G01X186475Y-287735D02*
Y-282735D01*
X189389Y-287735D01*
Y-282735D01*
G01X193032Y-287902D02*
X192905Y-287818D01*
Y-287652D01*
X193032Y-287568D01*
X193159Y-287652D01*
Y-287818D01*
X193032Y-287902D01*
G01Y-285652D02*
X192905Y-285568D01*
Y-285402D01*
X193032Y-285318D01*
X193159Y-285402D01*
Y-285568D01*
X193032Y-285652D01*
G01X170832Y-277735D02*
X370832D01*
G01X176465Y-262735D02*
Y-257735D01*
X177985D01*
X178492Y-257985D01*
X178872Y-258568D01*
X178999Y-259235D01*
X178872Y-259902D01*
X178555Y-260402D01*
X177985Y-260652D01*
X176465D01*
G01X181565Y-262735D02*
Y-257735D01*
X183149D01*
X183655Y-257985D01*
X183972Y-258318D01*
X184099Y-258985D01*
X183972Y-259652D01*
X183592Y-260068D01*
X183149Y-260318D01*
X181565D01*
G01X183149D02*
X184099Y-262735D01*
G01X187932D02*
X187425Y-262652D01*
X186982Y-262318D01*
X186602Y-261818D01*
X186349Y-261235D01*
X186222Y-260568D01*
Y-259902D01*
X186349Y-259235D01*
X186602Y-258652D01*
X186982Y-258152D01*
X187425Y-257818D01*
X187932Y-257735D01*
X188439Y-257818D01*
X188882Y-258152D01*
X189262Y-258652D01*
X189515Y-259235D01*
X189642Y-259902D01*
Y-260568D01*
X189515Y-261235D01*
X189262Y-261818D01*
X188882Y-262318D01*
X188439Y-262652D01*
X187932Y-262735D01*
G01X191765Y-261735D02*
X192082Y-262235D01*
X192462Y-262568D01*
X192905Y-262735D01*
X193412Y-262568D01*
X193792Y-262235D01*
X194172Y-261735D01*
X194299Y-261068D01*
Y-257735D01*
G01X199399Y-262735D02*
X196865D01*
Y-257735D01*
X199399D01*
G01X198385Y-260152D02*
X196865D01*
G01X204625Y-258152D02*
X204245Y-257902D01*
X203802Y-257735D01*
X203295D01*
X202725Y-257985D01*
X202282Y-258402D01*
X201965Y-258902D01*
X201712Y-259735D01*
X201649Y-260485D01*
X201775Y-261235D01*
X201965Y-261735D01*
X202345Y-262235D01*
X202789Y-262568D01*
X203232Y-262735D01*
X203675D01*
X204119Y-262568D01*
X204499Y-262318D01*
X204815Y-261985D01*
G01X208332Y-257735D02*
Y-262735D01*
G01X206875Y-257735D02*
X209789D01*
G01X213432Y-262902D02*
X213305Y-262818D01*
Y-262652D01*
X213432Y-262568D01*
X213559Y-262652D01*
Y-262818D01*
X213432Y-262902D01*
G01Y-260652D02*
X213305Y-260568D01*
Y-260402D01*
X213432Y-260318D01*
X213559Y-260402D01*
Y-260568D01*
X213432Y-260652D01*
G01X283832Y-302735D02*
Y-327735D01*
G01X288465Y-305235D02*
Y-310235D01*
X290999D01*
G01X294072Y-305235D02*
X295592D01*
G01X294832D02*
Y-310235D01*
G01X294072D02*
X295592D01*
G01X300439Y-307568D02*
X300692Y-307318D01*
X300882Y-306902D01*
X301009Y-306318D01*
X300882Y-305818D01*
X300629Y-305485D01*
X300185Y-305235D01*
X298475D01*
Y-310235D01*
X300565D01*
X301009Y-309902D01*
X301262Y-309402D01*
X301389Y-308818D01*
X301262Y-308235D01*
X300882Y-307735D01*
X300439Y-307568D01*
X298475D01*
G01X305032Y-310402D02*
X304905Y-310318D01*
Y-310152D01*
X305032Y-310068D01*
X305159Y-310152D01*
Y-310318D01*
X305032Y-310402D01*
G01Y-308152D02*
X304905Y-308068D01*
Y-307902D01*
X305032Y-307818D01*
X305159Y-307902D01*
Y-308068D01*
X305032Y-308152D01*
G01X328832Y-302735D02*
Y-327735D01*
G01X332732Y-305235D02*
Y-310235D01*
G01X331275Y-305235D02*
X334189D01*
G01X337832Y-310235D02*
X337452Y-310152D01*
X337072Y-309818D01*
X336819Y-309235D01*
X336692Y-308568D01*
X336819Y-307902D01*
X337072Y-307318D01*
X337452Y-306985D01*
X337832Y-306902D01*
X338212Y-306985D01*
X338592Y-307318D01*
X338845Y-307902D01*
X338909Y-308568D01*
X338845Y-309235D01*
X338592Y-309818D01*
X338212Y-310152D01*
X337832Y-310235D01*
G01X342932D02*
X342552Y-310152D01*
X342172Y-309818D01*
X341919Y-309235D01*
X341792Y-308568D01*
X341919Y-307902D01*
X342172Y-307318D01*
X342552Y-306985D01*
X342932Y-306902D01*
X343312Y-306985D01*
X343692Y-307318D01*
X343945Y-307902D01*
X344009Y-308568D01*
X343945Y-309235D01*
X343692Y-309818D01*
X343312Y-310152D01*
X342932Y-310235D01*
G01X348032D02*
Y-305235D01*
G01X353132Y-310402D02*
X353005Y-310318D01*
Y-310152D01*
X353132Y-310068D01*
X353259Y-310152D01*
Y-310318D01*
X353132Y-310402D01*
G01Y-308152D02*
X353005Y-308068D01*
Y-307902D01*
X353132Y-307818D01*
X353259Y-307902D01*
Y-308068D01*
X353132Y-308152D01*
G01X328832Y-277735D02*
Y-302735D01*
G01X331465Y-285235D02*
Y-280235D01*
X333049D01*
X333555Y-280485D01*
X333872Y-280818D01*
X333999Y-281485D01*
X333872Y-282152D01*
X333492Y-282568D01*
X333049Y-282818D01*
X331465D01*
G01X333049D02*
X333999Y-285235D01*
G01X339099D02*
X336565D01*
Y-280235D01*
X339099D01*
G01X338085Y-282652D02*
X336565D01*
G01X341349Y-280235D02*
X342932Y-285235D01*
X344515Y-280235D01*
G01X348032Y-285402D02*
X347905Y-285318D01*
Y-285152D01*
X348032Y-285068D01*
X348159Y-285152D01*
Y-285318D01*
X348032Y-285402D01*
G01Y-283152D02*
X347905Y-283068D01*
Y-282902D01*
X348032Y-282818D01*
X348159Y-282902D01*
Y-283068D01*
X348032Y-283152D01*
G01X351592Y-329435D02*
X351672Y-329360D01*
X351732Y-329235D01*
X351772Y-329060D01*
X351732Y-328910D01*
X351652Y-328810D01*
X351512Y-328735D01*
X350972D01*
Y-330235D01*
X351632D01*
X351772Y-330135D01*
X351852Y-329985D01*
X351892Y-329810D01*
X351852Y-329635D01*
X351732Y-329485D01*
X351592Y-329435D01*
X350972D01*
G01X352992Y-330235D02*
Y-329235D01*
G01Y-329410D02*
X352912Y-329310D01*
X352792Y-329260D01*
X352652Y-329235D01*
X352512Y-329285D01*
X352392Y-329385D01*
X352312Y-329535D01*
X352272Y-329735D01*
X352312Y-329935D01*
X352392Y-330085D01*
X352512Y-330185D01*
X352652Y-330235D01*
X352792Y-330210D01*
X352912Y-330135D01*
X352992Y-330035D01*
G01X353532Y-330060D02*
X353632Y-330160D01*
X353772Y-330235D01*
X353892D01*
X354012Y-330185D01*
X354092Y-330110D01*
X354132Y-330010D01*
X354112Y-329860D01*
X354032Y-329785D01*
X353672Y-329635D01*
X353592Y-329460D01*
X353632Y-329335D01*
X353712Y-329260D01*
X353832Y-329235D01*
X353952Y-329260D01*
X354072Y-329335D01*
G01X354732Y-329560D02*
X355372D01*
X355312Y-329385D01*
X355212Y-329285D01*
X355072Y-329235D01*
X354932Y-329260D01*
X354812Y-329335D01*
X354732Y-329510D01*
X354692Y-329660D01*
Y-329810D01*
X354732Y-329960D01*
X354832Y-330110D01*
X354952Y-330210D01*
X355092Y-330235D01*
X355232Y-330185D01*
X355372Y-330035D01*
G01X355872Y-330235D02*
Y-328735D01*
G01Y-329485D02*
X355972Y-329335D01*
X356092Y-329260D01*
X356212Y-329235D01*
X356392Y-329285D01*
X356512Y-329385D01*
X356592Y-329560D01*
Y-329760D01*
X356552Y-329960D01*
X356472Y-330110D01*
X356332Y-330210D01*
X356212Y-330235D01*
X356092Y-330210D01*
X355972Y-330135D01*
X355872Y-330010D01*
G01X357432Y-330235D02*
X357312Y-330210D01*
X357192Y-330110D01*
X357112Y-329935D01*
X357072Y-329735D01*
X357112Y-329535D01*
X357192Y-329360D01*
X357312Y-329260D01*
X357432Y-329235D01*
X357552Y-329260D01*
X357672Y-329360D01*
X357752Y-329535D01*
X357772Y-329735D01*
X357752Y-329935D01*
X357672Y-330110D01*
X357552Y-330210D01*
X357432Y-330235D01*
G01X358992D02*
Y-329235D01*
G01Y-329410D02*
X358912Y-329310D01*
X358792Y-329260D01*
X358652Y-329235D01*
X358512Y-329285D01*
X358392Y-329385D01*
X358312Y-329535D01*
X358272Y-329735D01*
X358312Y-329935D01*
X358392Y-330085D01*
X358512Y-330185D01*
X358652Y-330235D01*
X358792Y-330210D01*
X358912Y-330135D01*
X358992Y-330035D01*
G01X359552Y-330235D02*
Y-329235D01*
G01Y-329435D02*
X359652Y-329335D01*
X359752Y-329260D01*
X359892Y-329235D01*
X359992Y-329260D01*
X360112Y-329335D01*
G01X361392Y-328735D02*
Y-330235D01*
G01Y-330010D02*
X361312Y-330135D01*
X361192Y-330210D01*
X361052Y-330235D01*
X360892Y-330185D01*
X360772Y-330060D01*
X360692Y-329910D01*
X360672Y-329735D01*
X360692Y-329560D01*
X360772Y-329410D01*
X360892Y-329285D01*
X361052Y-329235D01*
X361192Y-329260D01*
X361292Y-329310D01*
X361392Y-329410D01*
G01X363032Y-330235D02*
Y-328735D01*
X363532D01*
X363692Y-328810D01*
X363792Y-328910D01*
X363832Y-329110D01*
X363792Y-329310D01*
X363672Y-329435D01*
X363532Y-329510D01*
X363032D01*
G01X363532D02*
X363832Y-330235D01*
G01X364332Y-329560D02*
X364972D01*
X364912Y-329385D01*
X364812Y-329285D01*
X364672Y-329235D01*
X364532Y-329260D01*
X364412Y-329335D01*
X364332Y-329510D01*
X364292Y-329660D01*
Y-329810D01*
X364332Y-329960D01*
X364432Y-330110D01*
X364552Y-330210D01*
X364692Y-330235D01*
X364832Y-330185D01*
X364972Y-330035D01*
G01X365472Y-329235D02*
X365832Y-330235D01*
X366192Y-329235D01*
G01X367032Y-330285D02*
X366992Y-330260D01*
Y-330210D01*
X367032Y-330185D01*
X367072Y-330210D01*
Y-330260D01*
X367032Y-330285D01*
G01X368192Y-330235D02*
X368232Y-329910D01*
X368292Y-329635D01*
X368372Y-329385D01*
X368472Y-329110D01*
X368632Y-328735D01*
X367832D01*
G01X369592Y-329435D02*
X369672Y-329360D01*
X369732Y-329235D01*
X369772Y-329060D01*
X369732Y-328910D01*
X369652Y-328810D01*
X369512Y-328735D01*
X368972D01*
Y-330235D01*
X369632D01*
X369772Y-330135D01*
X369852Y-329985D01*
X369892Y-329810D01*
X369852Y-329635D01*
X369732Y-329485D01*
X369592Y-329435D01*
X368972D01*
G01X-247901Y-428634D02*
Y1008173D01*
X2091018D01*
Y-428634D01*
X-247901D01*
G01X-115095Y-307460D02*
X-115565Y-307145D01*
X-116113Y-306935D01*
X-116740D01*
X-117445Y-307250D01*
X-117993Y-307775D01*
X-118385Y-308405D01*
X-118698Y-309455D01*
X-118776Y-310400D01*
X-118620Y-311345D01*
X-118385Y-311975D01*
X-117915Y-312605D01*
X-117366Y-313025D01*
X-116818Y-313235D01*
X-116270D01*
X-115721Y-313025D01*
X-115251Y-312710D01*
X-114860Y-312290D01*
G01X-111458Y-306935D02*
X-109578D01*
G01X-110518D02*
Y-313235D01*
G01X-111458D02*
X-109578D01*
G01X-104218Y-306935D02*
Y-313235D01*
G01X-106020Y-306935D02*
X-102416D01*
G01X-97918Y-313235D02*
Y-310400D01*
X-99485Y-306935D01*
G01X-96351D02*
X-97918Y-310400D01*
G01X-87041Y-311975D02*
X-86571Y-312710D01*
X-85945Y-313130D01*
X-85240Y-313235D01*
X-84613Y-313130D01*
X-83986Y-312605D01*
X-83595Y-311975D01*
X-83516Y-311345D01*
X-83673Y-310610D01*
X-84221Y-310085D01*
X-84770Y-309875D01*
X-85475D01*
G01X-84770D02*
X-84300Y-309560D01*
X-83908Y-309035D01*
X-83751Y-308405D01*
X-83908Y-307775D01*
X-84300Y-307250D01*
X-85005Y-306935D01*
X-85710Y-307040D01*
X-86415Y-307460D01*
G01X-80741Y-311975D02*
X-80271Y-312710D01*
X-79645Y-313130D01*
X-78940Y-313235D01*
X-78313Y-313130D01*
X-77686Y-312605D01*
X-77295Y-311975D01*
X-77216Y-311345D01*
X-77373Y-310610D01*
X-77921Y-310085D01*
X-78470Y-309875D01*
X-79175D01*
G01X-78470D02*
X-78000Y-309560D01*
X-77608Y-309035D01*
X-77451Y-308405D01*
X-77608Y-307775D01*
X-78000Y-307250D01*
X-78705Y-306935D01*
X-79410Y-307040D01*
X-80115Y-307460D01*
G01X-74441Y-311975D02*
X-73971Y-312710D01*
X-73345Y-313130D01*
X-72640Y-313235D01*
X-72013Y-313130D01*
X-71386Y-312605D01*
X-70995Y-311975D01*
X-70916Y-311345D01*
X-71073Y-310610D01*
X-71621Y-310085D01*
X-72170Y-309875D01*
X-72875D01*
G01X-72170D02*
X-71700Y-309560D01*
X-71308Y-309035D01*
X-71151Y-308405D01*
X-71308Y-307775D01*
X-71700Y-307250D01*
X-72405Y-306935D01*
X-73110Y-307040D01*
X-73815Y-307460D01*
G01X-66575Y-313235D02*
X-66418Y-311870D01*
X-66183Y-310715D01*
X-65870Y-309665D01*
X-65478Y-308510D01*
X-64851Y-306935D01*
X-67985D01*
G01X-60275Y-313235D02*
X-60118Y-311870D01*
X-59883Y-310715D01*
X-59570Y-309665D01*
X-59178Y-308510D01*
X-58551Y-306935D01*
X-61685D01*
G01X-53975Y-314390D02*
X-53661Y-313025D01*
G01X-47518Y-306935D02*
Y-313235D01*
G01X-49320Y-306935D02*
X-45716D01*
G01X-43176Y-313235D02*
X-41218Y-306935D01*
X-39260Y-313235D01*
G01X-39965Y-311030D02*
X-42471D01*
G01X-35858Y-306935D02*
X-33978D01*
G01X-34918D02*
Y-313235D01*
G01X-35858D02*
X-33978D01*
G01X-30968Y-306935D02*
X-29871Y-313235D01*
X-28618Y-306935D01*
X-27365Y-313235D01*
X-26268Y-306935D01*
G01X-24276Y-313235D02*
X-22318Y-306935D01*
X-20360Y-313235D01*
G01X-21065Y-311030D02*
X-23571D01*
G01X-17820Y-313235D02*
Y-306935D01*
X-14216Y-313235D01*
Y-306935D01*
G01X-3810Y-315335D02*
X-4593Y-314285D01*
X-4985Y-313235D01*
Y-309035D01*
X-4593Y-307985D01*
X-3810Y-306935D01*
G01X7615Y-313235D02*
Y-306935D01*
X9574D01*
X10200Y-307250D01*
X10592Y-307670D01*
X10749Y-308510D01*
X10592Y-309350D01*
X10122Y-309875D01*
X9574Y-310190D01*
X7615D01*
G01X9574D02*
X10749Y-313235D01*
G01X15482Y-313445D02*
X15325Y-313340D01*
Y-313130D01*
X15482Y-313025D01*
X15639Y-313130D01*
Y-313340D01*
X15482Y-313445D01*
G01X21782Y-313235D02*
X21155Y-313130D01*
X20607Y-312710D01*
X20137Y-312080D01*
X19824Y-311345D01*
X19667Y-310505D01*
Y-309665D01*
X19824Y-308825D01*
X20137Y-308090D01*
X20607Y-307460D01*
X21155Y-307040D01*
X21782Y-306935D01*
X22409Y-307040D01*
X22957Y-307460D01*
X23427Y-308090D01*
X23740Y-308825D01*
X23897Y-309665D01*
Y-310505D01*
X23740Y-311345D01*
X23427Y-312080D01*
X22957Y-312710D01*
X22409Y-313130D01*
X21782Y-313235D01*
G01X28082Y-313445D02*
X27925Y-313340D01*
Y-313130D01*
X28082Y-313025D01*
X28239Y-313130D01*
Y-313340D01*
X28082Y-313445D01*
G01X36105Y-307460D02*
X35635Y-307145D01*
X35087Y-306935D01*
X34460D01*
X33755Y-307250D01*
X33207Y-307775D01*
X32815Y-308405D01*
X32502Y-309455D01*
X32424Y-310400D01*
X32580Y-311345D01*
X32815Y-311975D01*
X33285Y-312605D01*
X33834Y-313025D01*
X34382Y-313235D01*
X34930D01*
X35479Y-313025D01*
X35949Y-312710D01*
X36340Y-312290D01*
G01X40682Y-313445D02*
X40525Y-313340D01*
Y-313130D01*
X40682Y-313025D01*
X40839Y-313130D01*
Y-313340D01*
X40682Y-313445D01*
G01X47374Y-315335D02*
X48157Y-314285D01*
X48549Y-313235D01*
Y-309035D01*
X48157Y-307985D01*
X47374Y-306935D01*
G01X-118620Y-293235D02*
Y-286935D01*
X-115016Y-293235D01*
Y-286935D01*
G01X-110518Y-293235D02*
X-111145Y-293130D01*
X-111693Y-292710D01*
X-112163Y-292080D01*
X-112476Y-291345D01*
X-112633Y-290505D01*
Y-289665D01*
X-112476Y-288825D01*
X-112163Y-288090D01*
X-111693Y-287460D01*
X-111145Y-287040D01*
X-110518Y-286935D01*
X-109891Y-287040D01*
X-109343Y-287460D01*
X-108873Y-288090D01*
X-108560Y-288825D01*
X-108403Y-289665D01*
Y-290505D01*
X-108560Y-291345D01*
X-108873Y-292080D01*
X-109343Y-292710D01*
X-109891Y-293130D01*
X-110518Y-293235D01*
G01X-104218Y-293445D02*
X-104375Y-293340D01*
Y-293130D01*
X-104218Y-293025D01*
X-104061Y-293130D01*
Y-293340D01*
X-104218Y-293445D01*
G01X-99406Y-287985D02*
X-98936Y-287355D01*
X-98388Y-287040D01*
X-97761Y-286935D01*
X-96978Y-287145D01*
X-96430Y-287670D01*
X-96273Y-288300D01*
X-96351Y-288930D01*
X-96665Y-289455D01*
X-98231Y-290505D01*
X-98936Y-291240D01*
X-99406Y-292290D01*
X-99563Y-293235D01*
X-96273D01*
G01X-91618D02*
Y-286935D01*
X-92558Y-288195D01*
G01Y-293235D02*
X-90678D01*
G01X-85318D02*
Y-286935D01*
X-86258Y-288195D01*
G01Y-293235D02*
X-84378D01*
G01X-79175Y-294390D02*
X-78861Y-293025D01*
G01X-75068Y-286935D02*
X-73971Y-293235D01*
X-72718Y-286935D01*
X-71465Y-293235D01*
X-70368Y-286935D01*
G01X-64851Y-293235D02*
X-67985D01*
Y-286935D01*
X-64851D01*
G01X-66105Y-289980D02*
X-67985D01*
G01X-61920Y-293235D02*
Y-286935D01*
X-58316Y-293235D01*
Y-286935D01*
G01X-55463Y-293235D02*
Y-286935D01*
G01X-52173D02*
Y-293235D01*
G01Y-290085D02*
X-55463D01*
G01X-49241Y-286935D02*
Y-291450D01*
X-48928Y-292395D01*
X-48301Y-293025D01*
X-47518Y-293235D01*
X-46735Y-293025D01*
X-46108Y-292395D01*
X-45795Y-291450D01*
Y-286935D01*
G01X-43176Y-293235D02*
X-41218Y-286935D01*
X-39260Y-293235D01*
G01X-39965Y-291030D02*
X-42471D01*
G01X-30106Y-287985D02*
X-29636Y-287355D01*
X-29088Y-287040D01*
X-28461Y-286935D01*
X-27678Y-287145D01*
X-27130Y-287670D01*
X-26973Y-288300D01*
X-27051Y-288930D01*
X-27365Y-289455D01*
X-28931Y-290505D01*
X-29636Y-291240D01*
X-30106Y-292290D01*
X-30263Y-293235D01*
X-26973D01*
G01X-24120D02*
Y-286935D01*
X-20516Y-293235D01*
Y-286935D01*
G01X-17741Y-293235D02*
Y-286935D01*
X-16175D01*
X-15548Y-287250D01*
X-15078Y-287670D01*
X-14686Y-288300D01*
X-14373Y-289035D01*
X-14295Y-290085D01*
X-14373Y-291135D01*
X-14686Y-291870D01*
X-15078Y-292500D01*
X-15548Y-292920D01*
X-16175Y-293235D01*
X-17741D01*
G01X-4985D02*
Y-286935D01*
X-3026D01*
X-2400Y-287250D01*
X-2008Y-287670D01*
X-1851Y-288510D01*
X-2008Y-289350D01*
X-2478Y-289875D01*
X-3026Y-290190D01*
X-4985D01*
G01X-3026D02*
X-1851Y-293235D01*
G01X1159D02*
Y-286935D01*
X2725D01*
X3352Y-287250D01*
X3822Y-287670D01*
X4214Y-288300D01*
X4527Y-289035D01*
X4605Y-290085D01*
X4527Y-291135D01*
X4214Y-291870D01*
X3822Y-292500D01*
X3352Y-292920D01*
X2725Y-293235D01*
X1159D01*
G01X9182Y-293445D02*
X9025Y-293340D01*
Y-293130D01*
X9182Y-293025D01*
X9339Y-293130D01*
Y-293340D01*
X9182Y-293445D01*
G01X-116348Y-300085D02*
X-114781D01*
Y-301975D01*
X-115251Y-302605D01*
X-115800Y-303025D01*
X-116583Y-303235D01*
X-117366Y-303025D01*
X-117915Y-302605D01*
X-118385Y-301975D01*
X-118698Y-301240D01*
X-118855Y-300400D01*
Y-299665D01*
X-118698Y-299035D01*
X-118385Y-298300D01*
X-117915Y-297670D01*
X-117445Y-297250D01*
X-116818Y-296935D01*
X-116270D01*
X-115643Y-297145D01*
X-115173Y-297565D01*
G01X-112241Y-296935D02*
Y-301450D01*
X-111928Y-302395D01*
X-111301Y-303025D01*
X-110518Y-303235D01*
X-109735Y-303025D01*
X-109108Y-302395D01*
X-108795Y-301450D01*
Y-296935D01*
G01X-105158D02*
X-103278D01*
G01X-104218D02*
Y-303235D01*
G01X-105158D02*
X-103278D01*
G01X-99563Y-302395D02*
X-98936Y-302920D01*
X-98231Y-303235D01*
X-97605D01*
X-96978Y-302920D01*
X-96508Y-302395D01*
X-96273Y-301660D01*
X-96430Y-300925D01*
X-96821Y-300295D01*
X-97526Y-299875D01*
X-98466Y-299665D01*
X-99015Y-299245D01*
X-99250Y-298510D01*
X-99093Y-297775D01*
X-98701Y-297250D01*
X-98153Y-296935D01*
X-97605D01*
X-97056Y-297145D01*
X-96586Y-297670D01*
G01X-93263Y-303235D02*
Y-296935D01*
G01X-89973D02*
Y-303235D01*
G01Y-300085D02*
X-93263D01*
G01X-87276Y-303235D02*
X-85318Y-296935D01*
X-83360Y-303235D01*
G01X-84065Y-301030D02*
X-86571D01*
G01X-80820Y-303235D02*
Y-296935D01*
X-77216Y-303235D01*
Y-296935D01*
G01X-68141Y-303235D02*
Y-296935D01*
X-66575D01*
X-65948Y-297250D01*
X-65478Y-297670D01*
X-65086Y-298300D01*
X-64773Y-299035D01*
X-64695Y-300085D01*
X-64773Y-301135D01*
X-65086Y-301870D01*
X-65478Y-302500D01*
X-65948Y-302920D01*
X-66575Y-303235D01*
X-68141D01*
G01X-61058Y-296935D02*
X-59178D01*
G01X-60118D02*
Y-303235D01*
G01X-61058D02*
X-59178D01*
G01X-55463Y-302395D02*
X-54836Y-302920D01*
X-54131Y-303235D01*
X-53505D01*
X-52878Y-302920D01*
X-52408Y-302395D01*
X-52173Y-301660D01*
X-52330Y-300925D01*
X-52721Y-300295D01*
X-53426Y-299875D01*
X-54366Y-299665D01*
X-54915Y-299245D01*
X-55150Y-298510D01*
X-54993Y-297775D01*
X-54601Y-297250D01*
X-54053Y-296935D01*
X-53505D01*
X-52956Y-297145D01*
X-52486Y-297670D01*
G01X-47518Y-296935D02*
Y-303235D01*
G01X-49320Y-296935D02*
X-45716D01*
G01X-41218Y-303445D02*
X-41375Y-303340D01*
Y-303130D01*
X-41218Y-303025D01*
X-41061Y-303130D01*
Y-303340D01*
X-41218Y-303445D01*
G01X-35075Y-304390D02*
X-34761Y-303025D01*
G01X-28618Y-296935D02*
Y-303235D01*
G01X-30420Y-296935D02*
X-26816D01*
G01X-24276Y-303235D02*
X-22318Y-296935D01*
X-20360Y-303235D01*
G01X-21065Y-301030D02*
X-23571D01*
G01X-16018Y-303235D02*
X-16645Y-303130D01*
X-17193Y-302710D01*
X-17663Y-302080D01*
X-17976Y-301345D01*
X-18133Y-300505D01*
Y-299665D01*
X-17976Y-298825D01*
X-17663Y-298090D01*
X-17193Y-297460D01*
X-16645Y-297040D01*
X-16018Y-296935D01*
X-15391Y-297040D01*
X-14843Y-297460D01*
X-14373Y-298090D01*
X-14060Y-298825D01*
X-13903Y-299665D01*
Y-300505D01*
X-14060Y-301345D01*
X-14373Y-302080D01*
X-14843Y-302710D01*
X-15391Y-303130D01*
X-16018Y-303235D01*
G01X-9718D02*
Y-300400D01*
X-11285Y-296935D01*
G01X-8151D02*
X-9718Y-300400D01*
G01X-5141Y-296935D02*
Y-301450D01*
X-4828Y-302395D01*
X-4201Y-303025D01*
X-3418Y-303235D01*
X-2635Y-303025D01*
X-2008Y-302395D01*
X-1695Y-301450D01*
Y-296935D01*
G01X924Y-303235D02*
X2882Y-296935D01*
X4840Y-303235D01*
G01X4135Y-301030D02*
X1629D01*
G01X7380Y-303235D02*
Y-296935D01*
X10984Y-303235D01*
Y-296935D01*
G01X-94518Y-282535D02*
X-97038Y-282118D01*
X-99243Y-280452D01*
X-101133Y-277952D01*
X-102393Y-275035D01*
X-103023Y-271702D01*
Y-268368D01*
X-102393Y-265035D01*
X-101133Y-262118D01*
X-99243Y-259619D01*
X-97038Y-257952D01*
X-94518Y-257535D01*
X-91998Y-257952D01*
X-89793Y-259619D01*
X-87903Y-262118D01*
X-86643Y-265035D01*
X-86013Y-268368D01*
Y-271702D01*
X-86643Y-275035D01*
X-87903Y-277952D01*
X-89793Y-280452D01*
X-91998Y-282118D01*
X-94518Y-282535D01*
G01X-91998Y-275868D02*
X-88218Y-282535D01*
G01X-74673Y-265869D02*
Y-277535D01*
X-73413Y-280452D01*
X-71523Y-282118D01*
X-69318Y-282535D01*
X-67113Y-282118D01*
X-65223Y-280452D01*
X-63963Y-277535D01*
G01Y-282535D02*
Y-265869D01*
G01X-38448Y-282535D02*
Y-265869D01*
G01Y-268785D02*
X-39708Y-267119D01*
X-41598Y-266285D01*
X-43803Y-265869D01*
X-46008Y-266702D01*
X-47898Y-268368D01*
X-49158Y-270869D01*
X-49788Y-274202D01*
X-49158Y-277535D01*
X-47898Y-280036D01*
X-46008Y-281702D01*
X-43803Y-282535D01*
X-41598Y-282118D01*
X-39708Y-280869D01*
X-38448Y-279202D01*
G01X-24273Y-282535D02*
Y-265869D01*
G01Y-270035D02*
X-23013Y-267952D01*
X-21123Y-266285D01*
X-18603Y-265869D01*
X-16398Y-266285D01*
X-14508Y-267952D01*
X-13563Y-270869D01*
Y-282535D01*
G01X6282Y-257535D02*
Y-282535D01*
G01X1872Y-265869D02*
X10692D01*
G01X37152Y-282535D02*
Y-265869D01*
G01Y-268785D02*
X35892Y-267119D01*
X34002Y-266285D01*
X31797Y-265869D01*
X29592Y-266702D01*
X27702Y-268368D01*
X26442Y-270869D01*
X25812Y-274202D01*
X26442Y-277535D01*
X27702Y-280036D01*
X29592Y-281702D01*
X31797Y-282535D01*
X34002Y-282118D01*
X35892Y-280869D01*
X37152Y-279202D01*
G01X76832Y-262235D02*
Y-270235D01*
X80832D01*
G01X88632D02*
Y-264902D01*
G01Y-265835D02*
X88232Y-265302D01*
X87632Y-265035D01*
X86932Y-264902D01*
X86232Y-265168D01*
X85632Y-265702D01*
X85232Y-266502D01*
X85032Y-267568D01*
X85232Y-268635D01*
X85632Y-269435D01*
X86232Y-269968D01*
X86932Y-270235D01*
X87632Y-270102D01*
X88232Y-269702D01*
X88632Y-269169D01*
G01X92732Y-272635D02*
X93332Y-272902D01*
X94132Y-272635D01*
X94632Y-272102D01*
X95032Y-271435D01*
X95632Y-269302D01*
X96932Y-264902D01*
G01X93732D02*
X95632Y-269302D01*
G01X101332Y-266635D02*
X104532D01*
X104232Y-265702D01*
X103732Y-265168D01*
X103032Y-264902D01*
X102332Y-265035D01*
X101732Y-265435D01*
X101332Y-266368D01*
X101132Y-267169D01*
Y-267968D01*
X101332Y-268768D01*
X101832Y-269568D01*
X102432Y-270102D01*
X103132Y-270235D01*
X103832Y-269968D01*
X104532Y-269169D01*
G01X109432Y-270235D02*
Y-264902D01*
G01Y-265968D02*
X109932Y-265435D01*
X110432Y-265035D01*
X111132Y-264902D01*
X111632Y-265035D01*
X112232Y-265435D01*
G01X95532Y-320235D02*
Y-312235D01*
X100132Y-320235D01*
Y-312235D01*
G01X105832Y-314902D02*
Y-320235D01*
G01Y-312768D02*
X105632Y-312635D01*
Y-312368D01*
X105832Y-312235D01*
X106032Y-312368D01*
Y-312635D01*
X105832Y-312768D01*
G01X112132Y-320235D02*
Y-314902D01*
G01Y-316235D02*
X112532Y-315568D01*
X113132Y-315035D01*
X113932Y-314902D01*
X114632Y-315035D01*
X115232Y-315568D01*
X115532Y-316502D01*
Y-320235D01*
G01X123632D02*
Y-314902D01*
G01Y-315835D02*
X123232Y-315302D01*
X122632Y-315035D01*
X121932Y-314902D01*
X121232Y-315168D01*
X120632Y-315702D01*
X120232Y-316502D01*
X120032Y-317568D01*
X120232Y-318635D01*
X120632Y-319435D01*
X121232Y-319968D01*
X121932Y-320235D01*
X122632Y-320102D01*
X123232Y-319702D01*
X123632Y-319169D01*
G01X110332Y-287235D02*
Y-295235D01*
G01X108032Y-287235D02*
X112632D01*
G01X118332Y-295235D02*
X117532Y-295102D01*
X116832Y-294568D01*
X116232Y-293768D01*
X115832Y-292835D01*
X115632Y-291768D01*
Y-290702D01*
X115832Y-289635D01*
X116232Y-288702D01*
X116832Y-287902D01*
X117532Y-287368D01*
X118332Y-287235D01*
X119132Y-287368D01*
X119832Y-287902D01*
X120432Y-288702D01*
X120832Y-289635D01*
X121032Y-290702D01*
Y-291768D01*
X120832Y-292835D01*
X120432Y-293768D01*
X119832Y-294568D01*
X119132Y-295102D01*
X118332Y-295235D01*
G01X124332D02*
Y-287235D01*
X126732D01*
X127532Y-287635D01*
X128132Y-288568D01*
X128332Y-289635D01*
X128132Y-290702D01*
X127632Y-291502D01*
X126732Y-291902D01*
X124332D01*
G01X130332Y-270235D02*
Y-262235D01*
X129132Y-263835D01*
G01Y-270235D02*
X131532D01*
G01X203432Y-313568D02*
X204032Y-312768D01*
X204732Y-312368D01*
X205532Y-312235D01*
X206532Y-312502D01*
X207232Y-313168D01*
X207432Y-313968D01*
X207332Y-314769D01*
X206932Y-315435D01*
X204932Y-316768D01*
X204032Y-317702D01*
X203432Y-319035D01*
X203232Y-320235D01*
X207432D01*
G01X213332Y-312235D02*
X212532Y-312502D01*
X211932Y-313168D01*
X211532Y-313968D01*
X211232Y-315035D01*
X211132Y-316235D01*
X211232Y-317435D01*
X211532Y-318502D01*
X211932Y-319302D01*
X212532Y-319968D01*
X213332Y-320235D01*
X214132Y-319968D01*
X214732Y-319302D01*
X215132Y-318502D01*
X215432Y-317435D01*
X215532Y-316235D01*
X215432Y-315035D01*
X215132Y-313968D01*
X214732Y-313168D01*
X214132Y-312502D01*
X213332Y-312235D01*
G01X219432Y-313568D02*
X220032Y-312768D01*
X220732Y-312368D01*
X221532Y-312235D01*
X222532Y-312502D01*
X223232Y-313168D01*
X223432Y-313968D01*
X223332Y-314769D01*
X222932Y-315435D01*
X220932Y-316768D01*
X220032Y-317702D01*
X219432Y-319035D01*
X219232Y-320235D01*
X223432D01*
G01X227432Y-313568D02*
X228032Y-312768D01*
X228732Y-312368D01*
X229532Y-312235D01*
X230532Y-312502D01*
X231232Y-313168D01*
X231432Y-313968D01*
X231332Y-314769D01*
X230932Y-315435D01*
X228932Y-316768D01*
X228032Y-317702D01*
X227432Y-319035D01*
X227232Y-320235D01*
X231432D01*
G01X235532Y-320502D02*
X239132Y-312235D01*
G01X245332Y-320235D02*
Y-312235D01*
X244132Y-313835D01*
G01Y-320235D02*
X246532D01*
G01X251432Y-313568D02*
X252032Y-312768D01*
X252732Y-312368D01*
X253532Y-312235D01*
X254532Y-312502D01*
X255232Y-313168D01*
X255432Y-313968D01*
X255332Y-314769D01*
X254932Y-315435D01*
X252932Y-316768D01*
X252032Y-317702D01*
X251432Y-319035D01*
X251232Y-320235D01*
X255432D01*
G01X259532Y-320502D02*
X263132Y-312235D01*
G01X269332D02*
X268532Y-312502D01*
X267932Y-313168D01*
X267532Y-313968D01*
X267232Y-315035D01*
X267132Y-316235D01*
X267232Y-317435D01*
X267532Y-318502D01*
X267932Y-319302D01*
X268532Y-319968D01*
X269332Y-320235D01*
X270132Y-319968D01*
X270732Y-319302D01*
X271132Y-318502D01*
X271432Y-317435D01*
X271532Y-316235D01*
X271432Y-315035D01*
X271132Y-313968D01*
X270732Y-313168D01*
X270132Y-312502D01*
X269332Y-312235D01*
G01X275632Y-319302D02*
X276332Y-319968D01*
X277132Y-320235D01*
X277932Y-319968D01*
X278632Y-319169D01*
X279132Y-317968D01*
X279332Y-316768D01*
Y-315302D01*
X279132Y-314102D01*
X278632Y-313035D01*
X278032Y-312502D01*
X277332Y-312235D01*
X276532Y-312502D01*
X275932Y-313035D01*
X275532Y-313835D01*
X275332Y-314902D01*
X275532Y-315835D01*
X276032Y-316768D01*
X276632Y-317302D01*
X277332Y-317435D01*
X278132Y-317169D01*
X278732Y-316502D01*
X279332Y-315302D01*
G01X205632Y-295235D02*
Y-287235D01*
X207632D01*
X208432Y-287635D01*
X209032Y-288168D01*
X209532Y-288968D01*
X209932Y-289902D01*
X210032Y-291235D01*
X209932Y-292568D01*
X209532Y-293502D01*
X209032Y-294302D01*
X208432Y-294835D01*
X207632Y-295235D01*
X205632D01*
G01X213332D02*
X215832Y-287235D01*
X218332Y-295235D01*
G01X217432Y-292435D02*
X214232D01*
G01X223832Y-287235D02*
X223032Y-287502D01*
X222432Y-288168D01*
X222032Y-288968D01*
X221732Y-290035D01*
X221632Y-291235D01*
X221732Y-292435D01*
X222032Y-293502D01*
X222432Y-294302D01*
X223032Y-294968D01*
X223832Y-295235D01*
X224632Y-294968D01*
X225232Y-294302D01*
X225632Y-293502D01*
X225932Y-292435D01*
X226032Y-291235D01*
X225932Y-290035D01*
X225632Y-288968D01*
X225232Y-288168D01*
X224632Y-287502D01*
X223832Y-287235D01*
G01X229932Y-295235D02*
Y-287235D01*
X233732D01*
G01X232332Y-291102D02*
X229932D01*
G01X239832Y-287235D02*
X239032Y-287502D01*
X238432Y-288168D01*
X238032Y-288968D01*
X237732Y-290035D01*
X237632Y-291235D01*
X237732Y-292435D01*
X238032Y-293502D01*
X238432Y-294302D01*
X239032Y-294968D01*
X239832Y-295235D01*
X240632Y-294968D01*
X241232Y-294302D01*
X241632Y-293502D01*
X241932Y-292435D01*
X242032Y-291235D01*
X241932Y-290035D01*
X241632Y-288968D01*
X241232Y-288168D01*
X240632Y-287502D01*
X239832Y-287235D01*
G01X247832D02*
Y-295235D01*
G01X245532Y-287235D02*
X250132D01*
G01X255832Y-295235D02*
Y-291635D01*
X253832Y-287235D01*
G01X257832D02*
X255832Y-291635D01*
G01X264632Y-290968D02*
X265032Y-290568D01*
X265332Y-289902D01*
X265532Y-288968D01*
X265332Y-288168D01*
X264932Y-287635D01*
X264232Y-287235D01*
X261532D01*
Y-295235D01*
X264832D01*
X265532Y-294702D01*
X265932Y-293902D01*
X266132Y-292968D01*
X265932Y-292035D01*
X265332Y-291235D01*
X264632Y-290968D01*
X261532D01*
G01X273032Y-295235D02*
Y-287235D01*
X269332Y-292968D01*
X274332D01*
G01X277632Y-295235D02*
Y-287235D01*
X279632D01*
X280432Y-287635D01*
X281032Y-288168D01*
X281532Y-288968D01*
X281932Y-289902D01*
X282032Y-291235D01*
X281932Y-292568D01*
X281532Y-293502D01*
X281032Y-294302D01*
X280432Y-294835D01*
X279632Y-295235D01*
X277632D01*
G01X287832Y-287235D02*
X287032Y-287502D01*
X286432Y-288168D01*
X286032Y-288968D01*
X285732Y-290035D01*
X285632Y-291235D01*
X285732Y-292435D01*
X286032Y-293502D01*
X286432Y-294302D01*
X287032Y-294968D01*
X287832Y-295235D01*
X288632Y-294968D01*
X289232Y-294302D01*
X289632Y-293502D01*
X289932Y-292435D01*
X290032Y-291235D01*
X289932Y-290035D01*
X289632Y-288968D01*
X289232Y-288168D01*
X288632Y-287502D01*
X287832Y-287235D01*
G01X233432Y-270235D02*
Y-262235D01*
X237232D01*
G01X235832Y-266102D02*
X233432D01*
G01X243332Y-262235D02*
X242532Y-262502D01*
X241932Y-263168D01*
X241532Y-263968D01*
X241232Y-265035D01*
X241132Y-266235D01*
X241232Y-267435D01*
X241532Y-268502D01*
X241932Y-269302D01*
X242532Y-269968D01*
X243332Y-270235D01*
X244132Y-269968D01*
X244732Y-269302D01*
X245132Y-268502D01*
X245432Y-267435D01*
X245532Y-266235D01*
X245432Y-265035D01*
X245132Y-263968D01*
X244732Y-263168D01*
X244132Y-262502D01*
X243332Y-262235D01*
G01X251332D02*
Y-270235D01*
G01X249032Y-262235D02*
X253632D01*
G01X256332Y-272902D02*
X262332D01*
G01X265332Y-270235D02*
Y-262235D01*
X267732D01*
X268532Y-262635D01*
X269132Y-263568D01*
X269332Y-264635D01*
X269132Y-265702D01*
X268632Y-266502D01*
X267732Y-266902D01*
X265332D01*
G01X272832Y-270235D02*
X275332Y-262235D01*
X277832Y-270235D01*
G01X276932Y-267435D02*
X273732D01*
G01X281032Y-270235D02*
Y-262235D01*
X285632Y-270235D01*
Y-262235D01*
G01X293332Y-270235D02*
X289332D01*
Y-262235D01*
X293332D01*
G01X291732Y-266102D02*
X289332D01*
G01X297332Y-262235D02*
Y-270235D01*
X301332D01*
G01X304332Y-272902D02*
X310332D01*
G01X316132Y-265968D02*
X316532Y-265568D01*
X316832Y-264902D01*
X317032Y-263968D01*
X316832Y-263168D01*
X316432Y-262635D01*
X315732Y-262235D01*
X313032D01*
Y-270235D01*
X316332D01*
X317032Y-269702D01*
X317432Y-268902D01*
X317632Y-267968D01*
X317432Y-267035D01*
X316832Y-266235D01*
X316132Y-265968D01*
X313032D01*
G01X321132Y-270235D02*
Y-262235D01*
X323132D01*
X323932Y-262635D01*
X324532Y-263168D01*
X325032Y-263968D01*
X325432Y-264902D01*
X325532Y-266235D01*
X325432Y-267568D01*
X325032Y-268502D01*
X324532Y-269302D01*
X323932Y-269835D01*
X323132Y-270235D01*
X321132D01*
G01X291832Y-323235D02*
Y-315235D01*
X290632Y-316835D01*
G01Y-323235D02*
X293032D01*
G01X297932Y-319902D02*
X298632Y-318968D01*
X299232Y-318435D01*
X300032Y-318168D01*
X300732Y-318435D01*
X301232Y-318968D01*
X301632Y-319768D01*
X301732Y-320702D01*
X301632Y-321502D01*
X301232Y-322302D01*
X300632Y-322968D01*
X299932Y-323235D01*
X299132Y-322968D01*
X298432Y-322169D01*
X298032Y-320968D01*
X297932Y-319635D01*
X298132Y-317902D01*
X298432Y-316968D01*
X298932Y-316035D01*
X299632Y-315368D01*
X300332Y-315235D01*
X301032Y-315502D01*
X301532Y-316168D01*
G01X307832Y-323502D02*
X307632Y-323368D01*
Y-323102D01*
X307832Y-322968D01*
X308032Y-323102D01*
Y-323368D01*
X307832Y-323502D01*
G01X313932Y-319902D02*
X314632Y-318968D01*
X315232Y-318435D01*
X316032Y-318168D01*
X316732Y-318435D01*
X317232Y-318968D01*
X317632Y-319768D01*
X317732Y-320702D01*
X317632Y-321502D01*
X317232Y-322302D01*
X316632Y-322968D01*
X315932Y-323235D01*
X315132Y-322968D01*
X314432Y-322169D01*
X314032Y-320968D01*
X313932Y-319635D01*
X314132Y-317902D01*
X314432Y-316968D01*
X314932Y-316035D01*
X315632Y-315368D01*
X316332Y-315235D01*
X317032Y-315502D01*
X317532Y-316168D01*
G01X336832Y-323235D02*
Y-315235D01*
X335632Y-316835D01*
G01Y-323235D02*
X338032D01*
G01X344632D02*
X344832Y-321502D01*
X345132Y-320035D01*
X345532Y-318702D01*
X346032Y-317235D01*
X346832Y-315235D01*
X342832D01*
G01X352832Y-323502D02*
X352632Y-323368D01*
Y-323102D01*
X352832Y-322968D01*
X353032Y-323102D01*
Y-323368D01*
X352832Y-323502D01*
G01X358932Y-316568D02*
X359532Y-315768D01*
X360232Y-315368D01*
X361032Y-315235D01*
X362032Y-315502D01*
X362732Y-316168D01*
X362932Y-316968D01*
X362832Y-317769D01*
X362432Y-318435D01*
X360432Y-319768D01*
X359532Y-320702D01*
X358932Y-322035D01*
X358732Y-323235D01*
X362932D01*
G01X356632Y-298235D02*
Y-290235D01*
X358632D01*
X359432Y-290635D01*
X360032Y-291168D01*
X360532Y-291968D01*
X360932Y-292902D01*
X361032Y-294235D01*
X360932Y-295568D01*
X360532Y-296502D01*
X360032Y-297302D01*
X359432Y-297835D01*
X358632Y-298235D01*
X356632D01*
G54D17*
X10516Y99500D03*
Y110500D03*
X14016Y192000D03*
Y184000D03*
X36016Y103500D03*
Y114500D03*
X22016Y221500D03*
Y213500D03*
Y229500D03*
Y241500D03*
Y233500D03*
Y237500D03*
Y245500D03*
X51516Y87500D03*
Y110000D03*
X42516Y247000D03*
X67516Y87000D03*
Y99000D03*
X61016Y177500D03*
Y181500D03*
Y185500D03*
Y193500D03*
Y189500D03*
X71016Y239500D03*
Y235500D03*
X60016Y265500D03*
X120854Y27211D03*
X143016Y92000D03*
Y84000D03*
Y76000D03*
Y108000D03*
Y100000D03*
G54D26*
X25984Y279449D03*
X136221Y43425D03*
G54D35*
X77453Y80437D03*
G54D44*
X94882Y82008D03*
G54D53*
X350500Y420150D03*
X340500D03*
X350500Y445150D03*
X340500D03*
Y597350D03*
X350500D03*
X340500Y622350D03*
X350500D03*
X380000Y316336D03*
X370000D03*
X380000Y341336D03*
X370000D03*
Y597350D03*
X380000D03*
X370000Y622350D03*
X380000D03*
G54D63*
G01X13575Y99500D02*
Y103500D01*
G01D02*
X15346D01*
X15405Y103559D01*
X19350D01*
G01X16000Y119500D02*
X9000D01*
X5500Y116000D01*
Y108000D01*
X7000Y106500D01*
X13000D01*
X13575Y105925D01*
Y103500D01*
G01Y110500D02*
Y114500D01*
G01D02*
X16821D01*
X16880Y114559D01*
X19350D01*
G01X25650Y112000D02*
X31000D01*
G01X35925Y114500D02*
X33500D01*
X31000Y112000D01*
G01X35925Y114500D02*
Y112575D01*
X36600Y111900D01*
Y109500D01*
G01X31000Y101000D02*
X25650D01*
G01X31000D02*
X33500Y103500D01*
X35925D01*
G01D02*
Y102075D01*
X36600Y101400D01*
Y98500D01*
G01X74075Y219500D02*
Y200414D01*
X84000Y190489D01*
Y136499D01*
X78500Y130999D01*
Y119759D01*
X77760Y119019D01*
X69482D01*
X67863Y120638D01*
X58137D01*
X56999Y119500D01*
X16000D01*
G01X59500Y117960D02*
X25460D01*
X22059Y114559D01*
X19350D01*
G01X22000Y190000D02*
X24000D01*
X25000Y191000D01*
X28567D01*
G01X22000Y190000D02*
X20000Y188000D01*
X17075D01*
G01D02*
Y184000D01*
G01X22000Y201000D02*
X20000D01*
X19000Y200000D01*
X17075D01*
G01X28567Y196000D02*
X22000D01*
G01D02*
X17075D01*
G01Y192000D02*
Y196000D01*
G01X25075Y217500D02*
Y221500D01*
G01X30000Y218500D02*
X32457D01*
X33000Y219043D01*
X36484D01*
G01X30000Y218500D02*
X28000D01*
X27000Y217500D01*
X25075D01*
G01Y213500D02*
Y209500D01*
G01X30000Y213500D02*
X32984Y216484D01*
X36484D01*
G01X25075Y213500D02*
X30000D01*
G01X17075Y204000D02*
Y200000D01*
G01X28567Y201000D02*
X22000D01*
G01X25075Y233500D02*
Y237500D01*
G01X30000Y236500D02*
X28000D01*
X27000Y237500D01*
X25075D01*
G01X30000Y236500D02*
X32543D01*
X33000Y236957D01*
X36484D01*
G01X25075Y245500D02*
Y241500D01*
G01X30000D02*
X25075D01*
G01X36484Y239516D02*
X31984D01*
X30000Y241500D01*
G01X25075Y225500D02*
Y229500D01*
G01X30000Y223500D02*
X31898Y221602D01*
X36484D01*
G01X25075Y225500D02*
X28000D01*
X30000Y223500D01*
G01X57480Y26299D02*
X61299D01*
X69400Y34400D01*
Y37100D01*
G01X43937Y20079D02*
X55882Y32024D01*
Y66163D01*
X51550Y76622D01*
X45500Y82672D01*
Y100500D01*
X44500Y101500D01*
Y104000D01*
G01X107318Y63176D02*
X108187Y62307D01*
Y58279D01*
X104233Y48733D01*
X96367Y40867D01*
X85923D01*
X83017Y43773D01*
Y48982D01*
X80999Y51000D01*
X67499D01*
X65000Y53499D01*
Y61000D01*
X66500Y62500D01*
Y65000D01*
X63000Y68500D01*
X59500D01*
X54575Y73425D01*
Y83500D01*
G01Y87500D02*
X51575Y90500D01*
X51500D01*
Y92260D01*
G01X54575Y83500D02*
Y87500D01*
G01X59500Y95000D02*
X54875D01*
X54059Y94184D01*
Y92260D01*
G01X42400Y86500D02*
Y93000D01*
G01X51500Y99740D02*
Y97524D01*
X50976Y97000D01*
X49500D01*
X48941Y97559D01*
Y99740D01*
G01X51425Y110000D02*
Y107445D01*
X51500Y107370D01*
Y105000D01*
G01Y99740D02*
Y105000D01*
G01X42400Y93000D02*
Y98500D01*
G01X44500Y104000D02*
X42400Y106100D01*
Y109500D01*
G01X56000Y186000D02*
X49433D01*
G01X60925Y181500D02*
X58001D01*
X56000Y183501D01*
Y186000D01*
G01Y196500D02*
X53603D01*
X53103Y196000D01*
X49433D01*
G01X60925Y193500D02*
X59000D01*
X56000Y196500D01*
G01Y191500D02*
X53500D01*
X53000Y191000D01*
X49433D01*
G01X56000Y191500D02*
X58000Y189500D01*
X60925D01*
G01X78340Y136000D02*
Y190660D01*
X59978Y209022D01*
X54436D01*
X52060Y211398D01*
Y244804D01*
X61256Y254000D01*
G01X80310Y138735D02*
Y191434D01*
X60782Y210962D01*
X55240D01*
X54000Y212202D01*
Y244000D01*
X60000Y250000D01*
X72500D01*
G01X42425Y247000D02*
Y238425D01*
X40957Y236957D01*
X36484D01*
G01X45575Y247000D02*
X48500D01*
X50500Y249000D01*
G01D02*
Y255343D01*
X58460Y274560D01*
X63400Y279500D01*
X90008D01*
X90748Y278760D01*
Y274803D01*
G01X77480Y26299D02*
Y35646D01*
X76755Y36371D01*
Y39441D01*
G01X68248Y47348D02*
Y42752D01*
X69400Y41600D01*
Y37100D01*
G01X64500Y63500D02*
X60241D01*
X59500Y62759D01*
Y60575D01*
G01X66925Y70000D02*
Y67500D01*
G01X59586Y51088D02*
Y54914D01*
X59500Y55000D01*
G01D02*
Y57425D01*
G01X70075Y64500D02*
Y67500D01*
G01X77382Y54227D02*
X73740D01*
X73000Y54967D01*
Y61575D01*
X70075Y64500D01*
G01X68720Y54000D02*
Y57967D01*
G01X101969Y52480D02*
Y55468D01*
X105193Y58692D01*
Y61657D01*
X103355Y63495D01*
X100768D01*
X97519Y60246D01*
X90851D01*
X82257Y68840D01*
X76161D01*
X73500Y71501D01*
Y75500D01*
X70760Y78240D01*
Y80437D01*
G01X101969Y60354D02*
X99521Y57906D01*
X89881D01*
X81287Y66500D01*
X75000D01*
X70760Y70740D01*
Y72563D01*
G01X73000Y91000D02*
X70575D01*
G01X75425D02*
X73000D01*
G01X65000Y73500D02*
Y75925D01*
G01X78575Y87000D02*
Y91000D01*
G01D02*
X81000D01*
G01X67425D02*
Y87000D01*
G01D02*
Y85575D01*
X70760Y82240D01*
Y80437D01*
G01X67425Y95000D02*
Y94916D01*
X65000Y92491D01*
Y84500D01*
X68000Y81500D01*
Y77501D01*
X70760Y74741D01*
Y72563D01*
G01X59500Y97425D02*
Y95000D01*
G01X75425D02*
X73000D01*
G01D02*
X70575D01*
G01X78575D02*
Y99000D01*
G01Y95000D02*
X81000D01*
G01X67425D02*
Y99000D01*
G01X66500Y181500D02*
X71000D01*
X73660Y178840D01*
Y125340D01*
X76000Y123000D01*
G01Y126500D02*
Y182000D01*
X72500Y185500D01*
X66500D01*
G01X60925Y181500D02*
Y177500D01*
G01X79000Y223500D02*
Y197667D01*
X86000Y190667D01*
Y135500D01*
X83500Y133000D01*
G01X64075Y181500D02*
X66500D01*
G01X64075Y185500D02*
X66500D01*
G01X60925Y193500D02*
Y197500D01*
G01Y189500D02*
Y185500D01*
G01X66000Y224500D02*
Y224425D01*
X70925Y219500D01*
G01X79000Y223500D02*
X74075D01*
G01X70925Y227500D02*
Y231500D01*
G01D02*
X68500D01*
G01D02*
X67293Y232000D01*
X64800D01*
X62402Y234398D01*
X59516D01*
G01X76500Y239500D02*
X74075D01*
G01X76500D02*
X77999D01*
X81500Y243001D01*
G01X74075Y235500D02*
X76500D01*
G01X81000D02*
X76500D01*
G01X66000Y224500D02*
X64561Y225939D01*
X63500Y228500D01*
X62720Y229280D01*
X59516D01*
G01X66000Y229500D02*
X64293Y230207D01*
X62661Y231839D01*
X59516D01*
G01X70925Y223500D02*
X68907Y225518D01*
X68146Y227354D01*
X66000Y229500D01*
G01X59516Y239516D02*
X65984D01*
X66000Y239500D01*
G01X70925D02*
X66000D01*
G01X59516Y236957D02*
X63543D01*
X66000Y234500D01*
G01D02*
X68500D01*
X69500Y235500D01*
X70925D01*
G01X82500Y262000D02*
Y260342D01*
X79424Y252916D01*
X77583Y251075D01*
X77500D01*
G01X61256Y254000D02*
X76500D01*
X78672Y256172D01*
X79600Y258413D01*
Y264458D01*
X74213Y269845D01*
Y274803D01*
G01X77500Y247925D02*
X74575D01*
X72500Y250000D01*
G01X76575Y274803D02*
Y270228D01*
X82500Y264303D01*
Y262000D01*
G01X84500Y76500D02*
Y77822D01*
X92766Y86088D01*
Y96412D01*
X86040Y103138D01*
Y125040D01*
X89000Y128000D01*
G01X81729Y77772D02*
X82957Y79000D01*
X83500D01*
X91226Y86726D01*
Y95774D01*
X84500Y102500D01*
Y127713D01*
X89380Y132593D01*
Y252405D01*
X95473Y267116D01*
Y274803D01*
G01X92500Y126000D02*
X97500Y121000D01*
Y115177D01*
X98437Y114240D01*
G01X101969Y76102D02*
Y79230D01*
X105097Y82358D01*
Y96255D01*
X96167Y105185D01*
Y111970D01*
X98437Y114240D01*
G01X101969Y83976D02*
Y96639D01*
X94227Y104381D01*
Y110576D01*
X90563Y114240D01*
G01X90925Y120000D02*
Y116850D01*
X90563Y116488D01*
Y114240D01*
G01X97835Y274803D02*
Y268794D01*
X90920Y252097D01*
Y129920D01*
X89000Y128000D01*
G01X83500Y129500D02*
X87840Y133840D01*
Y253620D01*
X90970Y261178D01*
Y266530D01*
X88386Y269114D01*
Y274803D01*
G01X88500Y123500D02*
X91499D01*
X94075Y120924D01*
Y120000D01*
G01X85500Y247925D02*
Y240000D01*
X81000Y235500D01*
G01X81500Y243001D02*
Y247925D01*
G01X85500Y251075D02*
Y254089D01*
X88500Y261330D01*
Y262000D01*
G01X83662Y274803D02*
Y270229D01*
X88500Y265391D01*
Y262000D01*
G01X83568Y256068D02*
X81500Y251075D01*
G01X81300Y274803D02*
Y269281D01*
X85500Y265081D01*
Y260733D01*
X83568Y256068D01*
G01X106954Y21716D02*
X122983D01*
G01X111965Y11716D02*
X122983D01*
G01Y16716D02*
X109812D01*
G01X121571Y112760D02*
X124720D01*
X125460Y112020D01*
Y107539D01*
X132999Y100000D01*
X137500D01*
G01X127500Y6716D02*
X143849D01*
G01X132000Y10500D02*
X134000D01*
X140216Y16716D01*
X143849D01*
G01X139500Y10500D02*
X140716Y11716D01*
X143849D01*
G01X142925Y80000D02*
Y76000D01*
G01Y80000D02*
X141500D01*
X137000Y84500D01*
G01X142925Y88000D02*
Y84000D01*
G01Y88000D02*
X137000D01*
G01X142925Y92000D02*
Y96000D01*
G01Y92000D02*
X137000D01*
G01X137500Y100000D02*
X142925D01*
G01X133000Y104000D02*
X127000Y110000D01*
Y115760D01*
X127740Y116500D01*
X130429D01*
G01X142925Y104000D02*
X133000D01*
G01X130429Y112760D02*
Y110500D01*
X133929Y107000D01*
X137500D01*
G01D02*
X139500D01*
X140500Y108000D01*
X142925D01*
G01X352033Y234525D02*
Y121123D01*
X351293Y120383D01*
X342716D01*
X342033Y121066D01*
Y127597D01*
X342773Y128337D01*
X348196D01*
X348936Y129077D01*
Y130737D01*
X348196Y131477D01*
X335563D01*
X334823Y132217D01*
Y133877D01*
X335563Y134617D01*
X348196D01*
X348936Y135357D01*
Y137017D01*
X348196Y137757D01*
X335870D01*
X335130Y138497D01*
Y140157D01*
X335870Y140897D01*
X348196D01*
X348936Y141637D01*
Y143297D01*
X348196Y144037D01*
X335870D01*
X335130Y144777D01*
Y146437D01*
X335870Y147177D01*
X348196D01*
X348936Y147917D01*
Y149577D01*
X348196Y150317D01*
X335870D01*
X335130Y151057D01*
Y152717D01*
X335870Y153457D01*
X348196D01*
X348936Y154197D01*
Y155857D01*
X348196Y156597D01*
X335870D01*
X335130Y157337D01*
Y158997D01*
X335870Y159737D01*
X348196D01*
X348936Y160477D01*
Y162137D01*
X348196Y162877D01*
X335870D01*
X335130Y163617D01*
Y165277D01*
X335870Y166017D01*
X348196D01*
X348936Y166757D01*
Y168417D01*
X348196Y169157D01*
X335870D01*
X335130Y169897D01*
Y171557D01*
X335870Y172297D01*
X348196D01*
X348936Y173037D01*
Y174697D01*
X348196Y175437D01*
X335870D01*
X335130Y176177D01*
Y177837D01*
X335870Y178577D01*
X348196D01*
X348936Y179317D01*
Y180977D01*
X348196Y181717D01*
X335870D01*
X335130Y182457D01*
Y184117D01*
X335870Y184857D01*
X348196D01*
X348936Y185597D01*
Y187257D01*
X348196Y187997D01*
X335870D01*
X335130Y188737D01*
Y190397D01*
X335870Y191137D01*
X348196D01*
X348936Y191877D01*
Y193537D01*
X348196Y194277D01*
X335870D01*
X335130Y195017D01*
Y196677D01*
X335870Y197417D01*
X348196D01*
X348936Y198157D01*
Y199817D01*
X348196Y200557D01*
X335870D01*
X335130Y201297D01*
Y202957D01*
X335870Y203697D01*
X348196D01*
X348936Y204437D01*
Y206097D01*
X348196Y206837D01*
X335870D01*
X335130Y207577D01*
Y209237D01*
X335870Y209977D01*
X348196D01*
X348936Y210717D01*
Y212377D01*
X348196Y213117D01*
X335563D01*
X334823Y213857D01*
Y215517D01*
X335563Y216257D01*
X341293D01*
X342033Y216997D01*
Y234525D01*
G54D18*
X13483Y99500D03*
Y110500D03*
X16983Y192000D03*
Y184000D03*
X24983Y221500D03*
Y213500D03*
Y229500D03*
Y241500D03*
Y233500D03*
Y237500D03*
Y245500D03*
X54483Y87500D03*
Y110000D03*
X38983Y103500D03*
Y114500D03*
X45483Y247000D03*
X70483Y87000D03*
Y99000D03*
X63983Y177500D03*
Y181500D03*
Y185500D03*
Y193500D03*
Y189500D03*
X73983Y239500D03*
Y235500D03*
X62983Y265500D03*
X123821Y27211D03*
X145983Y92000D03*
Y84000D03*
Y76000D03*
Y108000D03*
Y100000D03*
G54D54*
X345500Y431500D03*
X375000Y327686D03*
G54D45*
X98437Y107547D03*
X128385Y76431D03*
G54D36*
X77500Y250984D03*
G54D27*
X57480Y26299D03*
X67480D03*
G54D64*
G01X94882Y64291D02*
Y67148D01*
X95462Y67728D01*
X97166D01*
X101108Y71670D01*
X104279D01*
X106607Y73997D01*
X118048Y78737D01*
X123450D01*
X124986Y80271D01*
X124987Y81074D01*
X124988Y81076D01*
Y81342D01*
X124989Y81466D01*
X125606Y82082D01*
X127343D01*
X128385Y83124D01*
G01X94882Y72165D02*
Y69308D01*
X95462Y68728D01*
X96751D01*
X100693Y72670D01*
X103864D01*
X106040Y74846D01*
X108461Y75849D01*
X108894Y76895D01*
X110503Y77561D01*
X111548Y77128D01*
X113155Y77793D01*
X113588Y78839D01*
X115197Y79505D01*
X116242Y79072D01*
X117849Y79737D01*
X123036D01*
X123986Y80686D01*
X123987Y81311D01*
X123988Y81313D01*
Y81468D01*
X123373Y82086D01*
X121549D01*
X120511Y83124D01*
G01X102559Y274803D02*
Y272563D01*
X103241Y271881D01*
Y267807D01*
X101659Y265441D01*
X101658Y265439D01*
X100078Y263076D01*
X96032Y253305D01*
X102631Y115953D01*
X110894Y107690D01*
X121992Y103091D01*
X123948Y101135D01*
Y99530D01*
X122775Y98357D01*
Y97267D01*
G01X104922Y274803D02*
Y272562D01*
X104241Y271881D01*
Y267503D01*
X100965Y262602D01*
X97042Y253129D01*
X103612Y116387D01*
X111461Y108538D01*
X122559Y103939D01*
X124948Y101550D01*
Y99530D01*
X126121Y98357D01*
Y97267D01*
G01X120511Y83124D02*
X121988Y84601D01*
X123345D01*
X123948Y85204D01*
Y88312D01*
X122775Y89485D01*
Y90575D01*
G01X126121D02*
Y92117D01*
G01Y90575D02*
Y89485D01*
X124948Y88312D01*
Y85204D01*
X125551Y84601D01*
X126908D01*
X128385Y83124D01*
G01X122775Y92117D02*
Y90575D01*
G01Y95267D02*
Y97267D01*
G01X126121Y95267D02*
Y97267D01*
G01X346484Y607750D02*
Y606984D01*
X346000Y606500D01*
Y589975D01*
X346969Y589007D01*
X354524Y587675D01*
X355941Y585653D01*
X355160Y581221D01*
X353136Y579805D01*
X335568Y582902D01*
X334225Y581961D01*
X333588Y578346D01*
X334528Y577003D01*
X354376Y573505D01*
X355792Y571481D01*
X355011Y567051D01*
X352990Y565635D01*
X335301Y568753D01*
X333960Y567814D01*
X333323Y564199D01*
X334263Y562856D01*
X354508Y559286D01*
X355926Y557264D01*
X355143Y552832D01*
X353122Y551416D01*
X335534Y554517D01*
X334189Y553576D01*
X333551Y549962D01*
X334491Y548619D01*
X354514Y545090D01*
X355931Y543068D01*
X355148Y538635D01*
X353128Y537219D01*
X335374Y540350D01*
X334029Y539409D01*
X333393Y535796D01*
X334334Y534450D01*
X354442Y530906D01*
X355857Y528884D01*
X355077Y524453D01*
X353056Y523036D01*
X335026Y526218D01*
X333681Y525274D01*
X333043Y521660D01*
X333985Y520317D01*
X354496Y516702D01*
X355913Y514680D01*
X355130Y510247D01*
X353110Y508831D01*
X335052Y512016D01*
X333707Y511075D01*
X333071Y507462D01*
X334012Y506116D01*
X354445Y502514D01*
X355860Y500492D01*
X355080Y496061D01*
X353058Y494644D01*
X334998Y497829D01*
X333653Y496888D01*
X332945Y492863D01*
X333861Y491948D01*
X353982Y488400D01*
Y488401D01*
X354391Y488328D01*
X355806Y486306D01*
X355026Y481875D01*
X353004Y480458D01*
X334944Y483643D01*
X333599Y482702D01*
X332936Y478933D01*
X333805Y477761D01*
X344940Y475799D01*
X346000Y474536D01*
Y436000D01*
X346484Y435516D01*
Y434750D01*
G01X344516Y607750D02*
Y606984D01*
X345000Y606500D01*
Y589560D01*
X346485Y588076D01*
X353942Y586761D01*
X354883Y585418D01*
X354246Y581803D01*
X352902Y580862D01*
X335333Y583960D01*
X333311Y582543D01*
X332531Y578112D01*
X333946Y576090D01*
X353794Y572591D01*
X354735Y571247D01*
X354097Y567633D01*
X352755Y566692D01*
X335067Y569810D01*
X333047Y568396D01*
X332266Y563965D01*
X333681Y561943D01*
X353926Y558372D01*
X354868Y557029D01*
X354229Y553414D01*
X352887Y552474D01*
X335300Y555574D01*
X333276Y554158D01*
X332494Y549728D01*
X333909Y547706D01*
X353932Y544176D01*
X354873Y542833D01*
X354234Y539217D01*
X352893Y538276D01*
X335140Y541407D01*
X333116Y539991D01*
X332336Y535562D01*
X333752Y533537D01*
X353860Y529993D01*
X354800Y528650D01*
X354163Y525035D01*
X352821Y524093D01*
X334791Y527275D01*
X332768Y525855D01*
X332695Y525447D01*
X332696D01*
X331986Y521425D01*
X333403Y519403D01*
X353914Y515788D01*
X354855Y514445D01*
X354216Y510829D01*
X352875Y509888D01*
X334818Y513073D01*
X332794Y511657D01*
X332721Y511248D01*
X332722D01*
X332014Y507228D01*
X333430Y505203D01*
X353863Y501601D01*
X354803Y500258D01*
X354166Y496643D01*
X352823Y495702D01*
X334764Y498886D01*
X332740Y497470D01*
X331869Y492524D01*
X333376Y491017D01*
X353809Y487415D01*
X354749Y486072D01*
X354112Y482457D01*
X352769Y481516D01*
X334710Y484700D01*
X332686Y483284D01*
X331876Y478683D01*
X332566Y477752D01*
X332567Y477751D01*
X333239Y476845D01*
X344408Y474877D01*
X345000Y474171D01*
Y436000D01*
X344516Y435516D01*
Y434750D01*
G01X380195Y247618D02*
X376275D01*
X375695Y247038D01*
Y241917D01*
X374530Y240752D01*
X369533D01*
X368953Y240172D01*
Y238352D01*
X369533Y237772D01*
X381272D01*
X382437Y236607D01*
Y233957D01*
X381272Y232792D01*
X369533D01*
X368953Y232212D01*
Y230392D01*
X369533Y229812D01*
X381272D01*
X382437Y228647D01*
Y225997D01*
X381272Y224832D01*
X369533D01*
X368953Y224252D01*
Y222432D01*
X369533Y221852D01*
X381272D01*
X382437Y220687D01*
Y218037D01*
X381272Y216872D01*
X369533D01*
X368953Y216292D01*
Y214472D01*
X369533Y213892D01*
X381272D01*
X382437Y212727D01*
Y210077D01*
X381272Y208912D01*
X369533D01*
X368953Y208332D01*
Y206512D01*
X369533Y205932D01*
X381272D01*
X382437Y204767D01*
Y202117D01*
X381272Y200952D01*
X369533D01*
X368953Y200372D01*
Y198552D01*
X369533Y197972D01*
X381272D01*
X382437Y196807D01*
Y194157D01*
X381272Y192992D01*
X369533D01*
X368953Y192412D01*
Y190592D01*
X369533Y190012D01*
X381272D01*
X382437Y188847D01*
Y186197D01*
X381272Y185032D01*
X369533D01*
X368953Y184452D01*
Y182632D01*
X369533Y182052D01*
X381272D01*
X382437Y180887D01*
Y178237D01*
X381272Y177072D01*
X369533D01*
X368953Y176492D01*
Y174672D01*
X369533Y174092D01*
X381272D01*
X382437Y172927D01*
Y170277D01*
X381272Y169112D01*
X369533D01*
X368953Y168532D01*
Y166712D01*
X369533Y166132D01*
X381272D01*
X382437Y164967D01*
Y162317D01*
X381272Y161152D01*
X369533D01*
X368953Y160572D01*
Y158752D01*
X369533Y158172D01*
X381272D01*
X382437Y157007D01*
Y154357D01*
X381272Y153192D01*
X369533D01*
X368953Y152612D01*
Y150792D01*
X369533Y150212D01*
X381272D01*
X382437Y149047D01*
Y146397D01*
X381272Y145232D01*
X369533D01*
X368953Y144652D01*
Y142832D01*
X369533Y142252D01*
X381272D01*
X382437Y141087D01*
Y138437D01*
X381272Y137272D01*
X369533D01*
X368953Y136692D01*
Y134872D01*
X369533Y134292D01*
X381272D01*
X382437Y133127D01*
Y130477D01*
X381272Y129312D01*
X369334D01*
X368754Y128732D01*
Y126912D01*
X369334Y126332D01*
X381272D01*
X382437Y125167D01*
Y122517D01*
X381272Y121352D01*
X369533D01*
X368953Y120772D01*
Y118952D01*
X369533Y118372D01*
X381272D01*
X382437Y117207D01*
Y114557D01*
X381272Y113392D01*
X369135D01*
X368555Y112812D01*
Y110992D01*
X369135Y110412D01*
X381272D01*
X382437Y109247D01*
Y106597D01*
X381272Y105432D01*
X369069D01*
X368489Y104852D01*
Y103032D01*
X369069Y102452D01*
X374530D01*
X375695Y101287D01*
Y93580D01*
X376275Y93000D01*
X380195D01*
G01X370195Y247618D02*
X374115D01*
X374695Y247038D01*
Y242332D01*
X374115Y241752D01*
X369118D01*
X367953Y240587D01*
Y237937D01*
X369118Y236772D01*
X380857D01*
X381437Y236192D01*
Y234372D01*
X380857Y233792D01*
X369118D01*
X367953Y232627D01*
Y229977D01*
X369118Y228812D01*
X380857D01*
X381437Y228232D01*
Y226412D01*
X380857Y225832D01*
X369118D01*
X367953Y224667D01*
Y222017D01*
X369118Y220852D01*
X380857D01*
X381437Y220272D01*
Y218452D01*
X380857Y217872D01*
X369118D01*
X367953Y216707D01*
Y214057D01*
X369118Y212892D01*
X380857D01*
X381437Y212312D01*
Y210492D01*
X380857Y209912D01*
X369118D01*
X367953Y208747D01*
Y206097D01*
X369118Y204932D01*
X380857D01*
X381437Y204352D01*
Y202532D01*
X380857Y201952D01*
X369118D01*
X367953Y200787D01*
Y198137D01*
X369118Y196972D01*
X380857D01*
X381437Y196392D01*
Y194572D01*
X380857Y193992D01*
X369118D01*
X367953Y192827D01*
Y190177D01*
X369118Y189012D01*
X380857D01*
X381437Y188432D01*
Y186612D01*
X380857Y186032D01*
X369118D01*
X367953Y184867D01*
Y182217D01*
X369118Y181052D01*
X380857D01*
X381437Y180472D01*
Y178652D01*
X380857Y178072D01*
X369118D01*
X367953Y176907D01*
Y174257D01*
X369118Y173092D01*
X380857D01*
X381437Y172512D01*
Y170692D01*
X380857Y170112D01*
X369118D01*
X367953Y168947D01*
Y166297D01*
X369118Y165132D01*
X380857D01*
X381437Y164552D01*
Y162732D01*
X380857Y162152D01*
X369118D01*
X367953Y160987D01*
Y158337D01*
X369118Y157172D01*
X380857D01*
X381437Y156592D01*
Y154772D01*
X380857Y154192D01*
X369118D01*
X367953Y153027D01*
Y150377D01*
X369118Y149212D01*
X380857D01*
X381437Y148632D01*
Y146812D01*
X380857Y146232D01*
X369118D01*
X367953Y145067D01*
Y142417D01*
X369118Y141252D01*
X380857D01*
X381437Y140672D01*
Y138852D01*
X380857Y138272D01*
X369118D01*
X367953Y137107D01*
Y134457D01*
X369118Y133292D01*
X380857D01*
X381437Y132712D01*
Y130892D01*
X380857Y130312D01*
X368919D01*
X367754Y129147D01*
Y126497D01*
X368919Y125332D01*
X380857D01*
X381437Y124752D01*
Y122932D01*
X380857Y122352D01*
X369118D01*
X367953Y121187D01*
Y118537D01*
X369118Y117372D01*
X380857D01*
X381437Y116792D01*
Y114972D01*
X380857Y114392D01*
X368720D01*
X367555Y113227D01*
Y110577D01*
X368720Y109412D01*
X380857D01*
X381437Y108832D01*
Y107012D01*
X380857Y106432D01*
X368654D01*
X367489Y105267D01*
Y102617D01*
X368654Y101452D01*
X374115D01*
X374695Y100872D01*
Y93580D01*
X374115Y93000D01*
X370195D01*
G01X375984Y330936D02*
Y331702D01*
X375500Y332186D01*
Y349829D01*
X374441Y351092D01*
X363093Y353092D01*
X362152Y354436D01*
X362788Y358050D01*
X364134Y358992D01*
X384417Y355416D01*
X386437Y356831D01*
X386510Y357240D01*
X386509D01*
X387220Y361263D01*
X385804Y363283D01*
X363355Y367242D01*
X362414Y368585D01*
X363050Y372199D01*
X364397Y373141D01*
X384369Y369620D01*
X386389Y371035D01*
X387172Y375467D01*
X385756Y377487D01*
X363145Y381474D01*
X362204Y382818D01*
X362840Y386432D01*
X364186Y387374D01*
X384370Y383816D01*
X386390Y385230D01*
X387173Y389662D01*
X385757Y391683D01*
X363308Y395642D01*
X362368Y396985D01*
X363004Y400599D01*
X364350Y401541D01*
X384436Y397998D01*
X386456Y399414D01*
X387239Y403847D01*
X385822Y405869D01*
X363381Y409824D01*
X362440Y411168D01*
X363076Y414783D01*
X364420Y415724D01*
X384383Y412203D01*
X386404Y413620D01*
X387184Y418051D01*
X385769Y420073D01*
X363340Y424027D01*
X362399Y425371D01*
X363035Y428986D01*
X364380Y429927D01*
X384326Y426410D01*
X386347Y427826D01*
X387129Y432258D01*
X385712Y434276D01*
X363456Y438202D01*
X362515Y439545D01*
X363153Y443161D01*
X364496Y444102D01*
X384353Y440599D01*
X386375Y442016D01*
X387155Y446447D01*
X385740Y448469D01*
X363539Y452383D01*
X362598Y453727D01*
X363234Y457342D01*
X364579Y458283D01*
X384392Y454788D01*
X386412Y456204D01*
X387195Y460637D01*
X385778Y462659D01*
X363367Y466610D01*
X362427Y467953D01*
X363063Y471568D01*
X364408Y472509D01*
X384461Y468972D01*
X386481Y470388D01*
X387262Y474821D01*
X385847Y476842D01*
X363458Y480789D01*
X362517Y482133D01*
X363153Y485747D01*
X364498Y486688D01*
X384337Y483189D01*
X386359Y484606D01*
X387139Y489037D01*
X385724Y491059D01*
X363512Y494975D01*
X362571Y496321D01*
X363207Y499934D01*
X364552Y500875D01*
X384430Y497369D01*
X386450Y498785D01*
X387233Y503218D01*
X385816Y505240D01*
X363485Y509176D01*
X362543Y510519D01*
X363181Y514133D01*
X364526Y515077D01*
X384336Y511581D01*
X386357Y512998D01*
X387137Y517429D01*
X385722Y519451D01*
X363431Y523380D01*
X362490Y524726D01*
X363126Y528339D01*
X364471Y529280D01*
X384434Y525759D01*
X386453Y527175D01*
X387236Y531608D01*
X385819Y533631D01*
X363364Y537588D01*
X362424Y538932D01*
X363062Y542546D01*
X364406Y543487D01*
X384369Y539967D01*
X386390Y541383D01*
X387173Y545815D01*
X385755Y547837D01*
X363350Y551789D01*
X362410Y553131D01*
X363047Y556746D01*
X364388Y557685D01*
X384430Y554151D01*
X386452Y555567D01*
X387233Y559997D01*
X385817Y562020D01*
X363354Y565981D01*
X362414Y567324D01*
X363051Y570939D01*
X364394Y571880D01*
X384349Y568362D01*
X386372Y569778D01*
X387153Y574209D01*
X385737Y576231D01*
X376028Y577943D01*
X375500Y578572D01*
Y606500D01*
X375984Y606984D01*
Y607750D01*
G01X374016Y330936D02*
Y331702D01*
X374500Y332186D01*
Y349465D01*
X373909Y350170D01*
X362511Y352179D01*
X361095Y354202D01*
X361875Y358632D01*
X363900Y360049D01*
X384182Y356474D01*
X385524Y357413D01*
X386163Y361028D01*
X385222Y362369D01*
X362773Y366328D01*
X361357Y368350D01*
X362137Y372781D01*
X364163Y374198D01*
X384134Y370678D01*
X385476Y371617D01*
X386115Y375232D01*
X385174Y376573D01*
X362563Y380561D01*
X361147Y382584D01*
X361927Y387014D01*
X363952Y388431D01*
X384136Y384873D01*
X385477Y385812D01*
X386115Y389427D01*
X385175Y390769D01*
X362726Y394729D01*
X361311Y396750D01*
X362091Y401181D01*
X364116Y402598D01*
X384201Y399055D01*
X385542Y399996D01*
X386181Y403612D01*
X385240Y404955D01*
X362799Y408911D01*
X361383Y410934D01*
X362091Y414956D01*
X362090D01*
X362162Y415365D01*
X364186Y416781D01*
X384148Y413260D01*
X385490Y414202D01*
X386127Y417817D01*
X385187Y419160D01*
X362758Y423114D01*
X361342Y425137D01*
X362050Y429159D01*
X362049D01*
X362122Y429568D01*
X364146Y430984D01*
X384091Y427468D01*
X385433Y428408D01*
X386072Y432023D01*
X385131Y433363D01*
X362874Y437288D01*
X361457Y439310D01*
X362239Y443743D01*
X364261Y445160D01*
X384118Y441657D01*
X385461Y442598D01*
X386098Y446213D01*
X385158Y447556D01*
X362957Y451470D01*
X361541Y453493D01*
X362249Y457515D01*
X362248D01*
X362321Y457924D01*
X364345Y459340D01*
X384157Y455845D01*
X385498Y456786D01*
X386137Y460402D01*
X385196Y461745D01*
X362785Y465697D01*
X361370Y467719D01*
X362078Y471741D01*
X362077D01*
X362150Y472150D01*
X364174Y473566D01*
X384226Y470029D01*
X385567Y470970D01*
X386205Y474587D01*
X385265Y475929D01*
X362876Y479876D01*
X361460Y481899D01*
X362168Y485920D01*
X362167D01*
X362240Y486329D01*
X364264Y487745D01*
X384102Y484247D01*
X385445Y485188D01*
X386082Y488803D01*
X385142Y490146D01*
X362930Y494062D01*
X361514Y496087D01*
X362222Y500107D01*
X362221D01*
X362294Y500516D01*
X364318Y501932D01*
X384195Y498426D01*
X385536Y499367D01*
X386175Y502983D01*
X385234Y504326D01*
X362903Y508262D01*
X361486Y510284D01*
X362268Y514714D01*
X364291Y516134D01*
X384101Y512638D01*
X385443Y513580D01*
X386080Y517195D01*
X385140Y518538D01*
X362849Y522467D01*
X361433Y524492D01*
X362141Y528512D01*
X362140D01*
X362213Y528921D01*
X364237Y530337D01*
X384199Y526816D01*
X385539Y527757D01*
X386178Y531374D01*
X385237Y532717D01*
X362782Y536675D01*
X361367Y538698D01*
X362077Y542719D01*
X362076D01*
X362149Y543128D01*
X364172Y544544D01*
X384134Y541025D01*
X385477Y541965D01*
X386115Y545580D01*
X385173Y546923D01*
X362768Y550875D01*
X361353Y552896D01*
X362134Y557328D01*
X364154Y558742D01*
X384196Y555208D01*
X385539Y556149D01*
X386176Y559763D01*
X385235Y561107D01*
X362772Y565068D01*
X361357Y567090D01*
X361747Y569305D01*
X361746D01*
X361905Y570206D01*
X361906Y570208D01*
X362138Y571521D01*
X364159Y572938D01*
X384115Y569419D01*
X385459Y570360D01*
X386096Y573975D01*
X385155Y575318D01*
X375496Y577021D01*
X374500Y578207D01*
Y606500D01*
X374016Y606984D01*
Y607750D01*
G54D46*
X90563Y106760D03*
Y114240D03*
X98437D03*
X120511Y75644D03*
Y83124D03*
X128385D03*
G54D28*
X59586Y43608D03*
Y51088D03*
X68248Y47348D03*
X68720Y57967D03*
X77382Y61707D03*
Y54227D03*
G54D55*
X346484Y434750D03*
X344516D03*
Y607750D03*
X346484D03*
X375984Y330936D03*
X374016D03*
Y607750D03*
X375984D03*
G54D37*
X77500Y248017D03*
G54D19*
X20315Y20079D03*
X43937D03*
G54D29*
X54059Y92260D03*
X51500D03*
X48941D03*
Y99740D03*
X51500D03*
X54059D03*
G54D38*
X64764Y274803D03*
X67126D03*
X69489D03*
X71851D03*
X74213D03*
X76575D03*
X78937D03*
X64764Y284055D03*
X67126D03*
X69489D03*
X71851D03*
X74213D03*
X76575D03*
X78937D03*
X81300Y274803D03*
X83662D03*
X86024D03*
X88386D03*
X90748D03*
X93111D03*
X95473D03*
X97835D03*
X100197D03*
X81300Y284055D03*
X83662D03*
X86024D03*
X88386D03*
X90748D03*
X93111D03*
X95473D03*
X97835D03*
X100197D03*
X102559Y274803D03*
X104922D03*
X107284D03*
X102559Y284055D03*
X104922D03*
X107284D03*
G54D47*
X122983Y6716D03*
Y11716D03*
Y16716D03*
Y21716D03*
X143849Y6716D03*
Y21716D03*
Y16716D03*
Y11716D03*
G54D56*
X345500Y611000D03*
X375000D03*
G54D48*
X121571Y112760D03*
Y116500D03*
Y120240D03*
X130429Y112760D03*
Y120240D03*
Y116500D03*
G54D57*
X370195Y93000D03*
X380195D03*
Y247618D03*
X370195D03*
G54D39*
X64174Y294685D03*
X107874D03*
G54D49*
X126121Y90575D03*
X122775D03*
X126121Y97267D03*
X122775D03*
G54D58*
X370195Y83000D03*
X380195D03*
Y257618D03*
X370195D03*
G54D59*
G01X70575Y87000D02*
X73000D01*
G01D02*
X75425D01*
G01X63500Y100500D02*
Y95500D01*
X62000Y94000D01*
Y82075D01*
X65000Y79075D01*
G01X75425Y102000D02*
Y99000D01*
G01X70575D02*
X75425D01*
G01X78937Y284055D02*
Y287023D01*
X80119Y288205D01*
G01X64764Y284055D02*
Y288205D01*
G01X71851Y284055D02*
Y288205D01*
G01X78937Y274803D02*
Y270653D01*
G01X73638Y265563D02*
X73575Y265500D01*
G01X73638Y265563D02*
Y267139D01*
X71851Y268926D01*
G01D02*
Y274803D01*
G01X59925Y266426D02*
Y265500D01*
G01Y266426D02*
X64764Y271265D01*
Y274803D01*
G01X68308Y288205D02*
X69489Y287024D01*
Y284055D01*
G01X67126D02*
Y287023D01*
X68308Y288205D01*
G01X76575Y284055D02*
Y287024D01*
X75394Y288205D01*
G01D02*
X74213Y287024D01*
Y284055D01*
G01X100197Y274803D02*
Y270653D01*
G01Y284055D02*
Y287024D01*
X101378Y288205D01*
G01X80119D02*
X81300Y287024D01*
Y284055D01*
G01X93111D02*
Y288205D01*
G01X86024Y284055D02*
Y287024D01*
X84843Y288205D01*
G01D02*
X83662Y287024D01*
Y284055D01*
G01X86024Y274803D02*
Y270653D01*
G01X93111Y274803D02*
Y270653D01*
G01X95473Y284055D02*
Y287024D01*
X96654Y288205D01*
G01D02*
X97835Y287024D01*
Y284055D01*
G01X89567Y288205D02*
X90748Y287024D01*
Y284055D01*
G01X88386D02*
Y287024D01*
X89567Y288205D01*
G01X107284Y274803D02*
Y270653D01*
G01X106103Y288205D02*
X107284Y287024D01*
Y284055D01*
G01X104922D02*
Y287024D01*
X106103Y288205D01*
G01X101378D02*
X102559Y287024D01*
Y284055D01*
G01X148500Y108000D02*
X146075D01*
G01X148500Y100000D02*
X146075D01*
M02*
